G04 ================== begin FILE IDENTIFICATION RECORD ==================*
G04 Layout Name:  15968-1a.brd*
G04 Film Name:    L6*
G04 File Format:  Gerber RS274X*
G04 File Origin:  Cadence Allegro 16.5-S058*
G04 Origin Date:  Fri Oct 14 10:23:44 2016*
G04 *
G04 Layer:  VIA CLASS/BOTTOM*
G04 Layer:  PIN/BOTTOM*
G04 Layer:  ETCH/BOTTOM*
G04 Layer:  DRAWING FORMAT/LAYER_PCB_STORY*
G04 Layer:  DRAWING FORMAT/LAYER_L6*
G04 *
G04 Offset:    (0.00 0.00)*
G04 Mirror:    No*
G04 Mode:      Positive*
G04 Rotation:  0*
G04 FullContactRelief:  No*
G04 UndefLineWidth:     6.00*
G04 ================== end FILE IDENTIFICATION RECORD ====================*
%FSLAX35Y35*MOIN*%
%IR0*IPPOS*OFA0.00000B0.00000*MIA0B0*SFA1.00000B1.00000*%
%AMMACRO31*
4,1,40,.011,.007,
.011,-.007,
.010939,-.007695,
.010759,-.008368,
.010464,-.009,
.010064,-.009571,
.009571,-.010064,
.009,-.010464,
.008368,-.010759,
.007695,-.010939,
.007,-.011,
-.007,-.011,
-.007695,-.010939,
-.008368,-.010759,
-.009,-.010464,
-.009571,-.010064,
-.010064,-.009571,
-.010464,-.009,
-.010759,-.008368,
-.010939,-.007695,
-.011,-.007,
-.011,.007,
-.010939,.007695,
-.010759,.008368,
-.010464,.009,
-.010064,.009571,
-.009571,.010064,
-.009,.010464,
-.008368,.010759,
-.007695,.010939,
-.007,.011,
.007,.011,
.007695,.010939,
.008368,.010759,
.009,.010464,
.009571,.010064,
.010064,.009571,
.010464,.009,
.010759,.008368,
.010939,.007695,
.011,.007,
0.0*
%
%ADD31MACRO31*%
%AMMACRO12*
4,1,40,-.017,-.013,
-.017,.013,
-.016939,.013695,
-.016759,.014368,
-.016464,.015,
-.016064,.015571,
-.015571,.016064,
-.015,.016464,
-.014368,.016759,
-.013695,.016939,
-.013,.017,
.013,.017,
.013695,.016939,
.014368,.016759,
.015,.016464,
.015571,.016064,
.016064,.015571,
.016464,.015,
.016759,.014368,
.016939,.013695,
.017,.013,
.017,-.013,
.016939,-.013695,
.016759,-.014368,
.016464,-.015,
.016064,-.015571,
.015571,-.016064,
.015,-.016464,
.014368,-.016759,
.013695,-.016939,
.013,-.017,
-.013,-.017,
-.013695,-.016939,
-.014368,-.016759,
-.015,-.016464,
-.015571,-.016064,
-.016064,-.015571,
-.016464,-.015,
-.016759,-.014368,
-.016939,-.013695,
-.017,-.013,
0.0*
%
%ADD12MACRO12*%
%ADD17R,.022X.11*%
%ADD47R,.022X.102*%
%ADD10C,.01*%
%ADD16C,.02*%
%ADD45C,.04*%
%ADD41R,.05X.008*%
%ADD13C,.022*%
%ADD46C,.042*%
%AMMACRO36*
4,1,32,-.00137,.05008,
.025,.05008,
.025,.06208,
-.025,.06208,
-.025,-.06209,
.025,-.06209,
.025,-.05409,
-.00137,-.05409,
-.00137,-.04635,
.025,-.04635,
.025,-.03835,
-.00137,-.03835,
-.00137,-.0306,
.025,-.0306,
.025,-.0226,
-.00137,-.0226,
-.00137,-.01485,
.025,-.01485,
.025,-.00685,
-.00137,-.00685,
-.00137,.0009,
.025,.0009,
.025,.0089,
-.00137,.0089,
-.00137,.01665,
.025,.01665,
.025,.02465,
-.00137,.02465,
-.00137,.03239,
.025,.03239,
.025,.04039,
-.00137,.04039,
-.00137,.05008,
0.0*
%
%ADD36MACRO36*%
%ADD14C,.028*%
%AMMACRO28*
4,1,40,.007,-.011,
-.007,-.011,
-.007695,-.010939,
-.008368,-.010759,
-.009,-.010464,
-.009571,-.010064,
-.010064,-.009571,
-.010464,-.009,
-.010759,-.008368,
-.010939,-.007695,
-.011,-.007,
-.011,.007,
-.010939,.007695,
-.010759,.008368,
-.010464,.009,
-.010064,.009571,
-.009571,.010064,
-.009,.010464,
-.008368,.010759,
-.007695,.010939,
-.007,.011,
.007,.011,
.007695,.010939,
.008368,.010759,
.009,.010464,
.009571,.010064,
.010064,.009571,
.010464,.009,
.010759,.008368,
.010939,.007695,
.011,.007,
.011,-.007,
.010939,-.007695,
.010759,-.008368,
.010464,-.009,
.010064,-.009571,
.009571,-.010064,
.009,-.010464,
.008368,-.010759,
.007695,-.010939,
.007,-.011,
0.0*
%
%ADD28MACRO28*%
%AMMACRO23*
4,1,40,-.008,.012,
.008,.012,
.008695,.011939,
.009368,.011759,
.01,.011464,
.010571,.011064,
.011064,.010571,
.011464,.01,
.011759,.009368,
.011939,.008695,
.012,.008,
.012,-.008,
.011939,-.008695,
.011759,-.009368,
.011464,-.01,
.011064,-.010571,
.010571,-.011064,
.01,-.011464,
.009368,-.011759,
.008695,-.011939,
.008,-.012,
-.008,-.012,
-.008695,-.011939,
-.009368,-.011759,
-.01,-.011464,
-.010571,-.011064,
-.011064,-.010571,
-.011464,-.01,
-.011759,-.009368,
-.011939,-.008695,
-.012,-.008,
-.012,.008,
-.011939,.008695,
-.011759,.009368,
-.011464,.01,
-.011064,.010571,
-.010571,.011064,
-.01,.011464,
-.009368,.011759,
-.008695,.011939,
-.008,.012,
0.0*
%
%ADD23MACRO23*%
%AMMACRO34*
4,1,40,-.013,.017,
.013,.017,
.013695,.016939,
.014368,.016759,
.015,.016464,
.015571,.016064,
.016064,.015571,
.016464,.015,
.016759,.014368,
.016939,.013695,
.017,.013,
.017,-.013,
.016939,-.013695,
.016759,-.014368,
.016464,-.015,
.016064,-.015571,
.015571,-.016064,
.015,-.016464,
.014368,-.016759,
.013695,-.016939,
.013,-.017,
-.013,-.017,
-.013695,-.016939,
-.014368,-.016759,
-.015,-.016464,
-.015571,-.016064,
-.016064,-.015571,
-.016464,-.015,
-.016759,-.014368,
-.016939,-.013695,
-.017,-.013,
-.017,.013,
-.016939,.013695,
-.016759,.014368,
-.016464,.015,
-.016064,.015571,
-.015571,.016064,
-.015,.016464,
-.014368,.016759,
-.013695,.016939,
-.013,.017,
0.0*
%
%ADD34MACRO34*%
%AMMACRO43*
4,1,6,.025,-.0135,
.005,.0065,
.005,.0135,
-.005,.0135,
-.005,.0065,
-.025,-.0135,
.025,-.0135,
0.0*
%
%ADD43MACRO43*%
%AMMACRO19*
4,1,40,.017,.013,
.017,-.013,
.016939,-.013695,
.016759,-.014368,
.016464,-.015,
.016064,-.015571,
.015571,-.016064,
.015,-.016464,
.014368,-.016759,
.013695,-.016939,
.013,-.017,
-.013,-.017,
-.013695,-.016939,
-.014368,-.016759,
-.015,-.016464,
-.015571,-.016064,
-.016064,-.015571,
-.016464,-.015,
-.016759,-.014368,
-.016939,-.013695,
-.017,-.013,
-.017,.013,
-.016939,.013695,
-.016759,.014368,
-.016464,.015,
-.016064,.015571,
-.015571,.016064,
-.015,.016464,
-.014368,.016759,
-.013695,.016939,
-.013,.017,
.013,.017,
.013695,.016939,
.014368,.016759,
.015,.016464,
.015571,.016064,
.016064,.015571,
.016464,.015,
.016759,.014368,
.016939,.013695,
.017,.013,
0.0*
%
%ADD19MACRO19*%
%AMMACRO29*
4,1,40,.007,-.011,
-.007,-.011,
-.007695,-.010939,
-.008368,-.010759,
-.009,-.010464,
-.009571,-.010064,
-.010064,-.009571,
-.010464,-.009,
-.010759,-.008368,
-.010939,-.007695,
-.011,-.007,
-.011,.007,
-.010939,.007695,
-.010759,.008368,
-.010464,.009,
-.010064,.009571,
-.009571,.010064,
-.009,.010464,
-.008368,.010759,
-.007695,.010939,
-.007,.011,
.007,.011,
.007695,.010939,
.008368,.010759,
.009,.010464,
.009571,.010064,
.010064,.009571,
.010464,.009,
.010759,.008368,
.010939,.007695,
.011,.007,
.011,-.007,
.010939,-.007695,
.010759,-.008368,
.010464,-.009,
.010064,-.009571,
.009571,-.010064,
.009,-.010464,
.008368,-.010759,
.007695,-.010939,
.007,-.011,
0.0*
%
%ADD29MACRO29*%
%AMMACRO22*
4,1,40,-.008,.012,
.008,.012,
.008695,.011939,
.009368,.011759,
.01,.011464,
.010571,.011064,
.011064,.010571,
.011464,.01,
.011759,.009368,
.011939,.008695,
.012,.008,
.012,-.008,
.011939,-.008695,
.011759,-.009368,
.011464,-.01,
.011064,-.010571,
.010571,-.011064,
.01,-.011464,
.009368,-.011759,
.008695,-.011939,
.008,-.012,
-.008,-.012,
-.008695,-.011939,
-.009368,-.011759,
-.01,-.011464,
-.010571,-.011064,
-.011064,-.010571,
-.011464,-.01,
-.011759,-.009368,
-.011939,-.008695,
-.012,-.008,
-.012,.008,
-.011939,.008695,
-.011759,.009368,
-.011464,.01,
-.011064,.010571,
-.010571,.011064,
-.01,.011464,
-.009368,.011759,
-.008695,.011939,
-.008,.012,
0.0*
%
%ADD22MACRO22*%
%AMMACRO35*
4,1,40,-.013,.017,
.013,.017,
.013695,.016939,
.014368,.016759,
.015,.016464,
.015571,.016064,
.016064,.015571,
.016464,.015,
.016759,.014368,
.016939,.013695,
.017,.013,
.017,-.013,
.016939,-.013695,
.016759,-.014368,
.016464,-.015,
.016064,-.015571,
.015571,-.016064,
.015,-.016464,
.014368,-.016759,
.013695,-.016939,
.013,-.017,
-.013,-.017,
-.013695,-.016939,
-.014368,-.016759,
-.015,-.016464,
-.015571,-.016064,
-.016064,-.015571,
-.016464,-.015,
-.016759,-.014368,
-.016939,-.013695,
-.017,-.013,
-.017,.013,
-.016939,.013695,
-.016759,.014368,
-.016464,.015,
-.016064,.015571,
-.015571,.016064,
-.015,.016464,
-.014368,.016759,
-.013695,.016939,
-.013,.017,
0.0*
%
%ADD35MACRO35*%
%AMMACRO20*
4,1,40,.017,.013,
.017,-.013,
.016939,-.013695,
.016759,-.014368,
.016464,-.015,
.016064,-.015571,
.015571,-.016064,
.015,-.016464,
.014368,-.016759,
.013695,-.016939,
.013,-.017,
-.013,-.017,
-.013695,-.016939,
-.014368,-.016759,
-.015,-.016464,
-.015571,-.016064,
-.016064,-.015571,
-.016464,-.015,
-.016759,-.014368,
-.016939,-.013695,
-.017,-.013,
-.017,.013,
-.016939,.013695,
-.016759,.014368,
-.016464,.015,
-.016064,.015571,
-.015571,.016064,
-.015,.016464,
-.014368,.016759,
-.013695,.016939,
-.013,.017,
.013,.017,
.013695,.016939,
.014368,.016759,
.015,.016464,
.015571,.016064,
.016064,.015571,
.016464,.015,
.016759,.014368,
.016939,.013695,
.017,.013,
0.0*
%
%ADD20MACRO20*%
%ADD37R,.001X.001*%
%ADD40R,.05X.012*%
%ADD39R,.052X.012*%
%ADD48C,.101*%
%ADD18R,.138X.117*%
%ADD21R,.045X.055*%
%ADD44R,.055X.045*%
%ADD38R,.014X.089*%
%ADD15C,.374*%
%AMMACRO32*
4,1,40,-.007,.011,
.007,.011,
.007695,.010939,
.008368,.010759,
.009,.010464,
.009571,.010064,
.010064,.009571,
.010464,.009,
.010759,.008368,
.010939,.007695,
.011,.007,
.011,-.007,
.010939,-.007695,
.010759,-.008368,
.010464,-.009,
.010064,-.009571,
.009571,-.010064,
.009,-.010464,
.008368,-.010759,
.007695,-.010939,
.007,-.011,
-.007,-.011,
-.007695,-.010939,
-.008368,-.010759,
-.009,-.010464,
-.009571,-.010064,
-.010064,-.009571,
-.010464,-.009,
-.010759,-.008368,
-.010939,-.007695,
-.011,-.007,
-.011,.007,
-.010939,.007695,
-.010759,.008368,
-.010464,.009,
-.010064,.009571,
-.009571,.010064,
-.009,.010464,
-.008368,.010759,
-.007695,.010939,
-.007,.011,
0.0*
%
%ADD32MACRO32*%
%AMMACRO27*
4,1,40,.008,-.012,
-.008,-.012,
-.008695,-.011939,
-.009368,-.011759,
-.01,-.011464,
-.010571,-.011064,
-.011064,-.010571,
-.011464,-.01,
-.011759,-.009368,
-.011939,-.008695,
-.012,-.008,
-.012,.008,
-.011939,.008695,
-.011759,.009368,
-.011464,.01,
-.011064,.010571,
-.010571,.011064,
-.01,.011464,
-.009368,.011759,
-.008695,.011939,
-.008,.012,
.008,.012,
.008695,.011939,
.009368,.011759,
.01,.011464,
.010571,.011064,
.011064,.010571,
.011464,.01,
.011759,.009368,
.011939,.008695,
.012,.008,
.012,-.008,
.011939,-.008695,
.011759,-.009368,
.011464,-.01,
.011064,-.010571,
.010571,-.011064,
.01,-.011464,
.009368,-.011759,
.008695,-.011939,
.008,-.012,
0.0*
%
%ADD27MACRO27*%
%AMMACRO25*
4,1,40,.012,.008,
.012,-.008,
.011939,-.008695,
.011759,-.009368,
.011464,-.01,
.011064,-.010571,
.010571,-.011064,
.01,-.011464,
.009368,-.011759,
.008695,-.011939,
.008,-.012,
-.008,-.012,
-.008695,-.011939,
-.009368,-.011759,
-.01,-.011464,
-.010571,-.011064,
-.011064,-.010571,
-.011464,-.01,
-.011759,-.009368,
-.011939,-.008695,
-.012,-.008,
-.012,.008,
-.011939,.008695,
-.011759,.009368,
-.011464,.01,
-.011064,.010571,
-.010571,.011064,
-.01,.011464,
-.009368,.011759,
-.008695,.011939,
-.008,.012,
.008,.012,
.008695,.011939,
.009368,.011759,
.01,.011464,
.010571,.011064,
.011064,.010571,
.011464,.01,
.011759,.009368,
.011939,.008695,
.012,.008,
0.0*
%
%ADD25MACRO25*%
%AMMACRO30*
4,1,40,.011,.007,
.011,-.007,
.010939,-.007695,
.010759,-.008368,
.010464,-.009,
.010064,-.009571,
.009571,-.010064,
.009,-.010464,
.008368,-.010759,
.007695,-.010939,
.007,-.011,
-.007,-.011,
-.007695,-.010939,
-.008368,-.010759,
-.009,-.010464,
-.009571,-.010064,
-.010064,-.009571,
-.010464,-.009,
-.010759,-.008368,
-.010939,-.007695,
-.011,-.007,
-.011,.007,
-.010939,.007695,
-.010759,.008368,
-.010464,.009,
-.010064,.009571,
-.009571,.010064,
-.009,.010464,
-.008368,.010759,
-.007695,.010939,
-.007,.011,
.007,.011,
.007695,.010939,
.008368,.010759,
.009,.010464,
.009571,.010064,
.010064,.009571,
.010464,.009,
.010759,.008368,
.010939,.007695,
.011,.007,
0.0*
%
%ADD30MACRO30*%
%AMMACRO11*
4,1,40,-.017,-.013,
-.017,.013,
-.016939,.013695,
-.016759,.014368,
-.016464,.015,
-.016064,.015571,
-.015571,.016064,
-.015,.016464,
-.014368,.016759,
-.013695,.016939,
-.013,.017,
.013,.017,
.013695,.016939,
.014368,.016759,
.015,.016464,
.015571,.016064,
.016064,.015571,
.016464,.015,
.016759,.014368,
.016939,.013695,
.017,.013,
.017,-.013,
.016939,-.013695,
.016759,-.014368,
.016464,-.015,
.016064,-.015571,
.015571,-.016064,
.015,-.016464,
.014368,-.016759,
.013695,-.016939,
.013,-.017,
-.013,-.017,
-.013695,-.016939,
-.014368,-.016759,
-.015,-.016464,
-.015571,-.016064,
-.016064,-.015571,
-.016464,-.015,
-.016759,-.014368,
-.016939,-.013695,
-.017,-.013,
0.0*
%
%ADD11MACRO11*%
%AMMACRO42*
4,1,6,.005,-.0135,
.005,-.0065,
.025,.0135,
-.025,.0135,
-.005,-.0065,
-.005,-.0135,
.005,-.0135,
0.0*
%
%ADD42MACRO42*%
%AMMACRO33*
4,1,40,-.007,.011,
.007,.011,
.007695,.010939,
.008368,.010759,
.009,.010464,
.009571,.010064,
.010064,.009571,
.010464,.009,
.010759,.008368,
.010939,.007695,
.011,.007,
.011,-.007,
.010939,-.007695,
.010759,-.008368,
.010464,-.009,
.010064,-.009571,
.009571,-.010064,
.009,-.010464,
.008368,-.010759,
.007695,-.010939,
.007,-.011,
-.007,-.011,
-.007695,-.010939,
-.008368,-.010759,
-.009,-.010464,
-.009571,-.010064,
-.010064,-.009571,
-.010464,-.009,
-.010759,-.008368,
-.010939,-.007695,
-.011,-.007,
-.011,.007,
-.010939,.007695,
-.010759,.008368,
-.010464,.009,
-.010064,.009571,
-.009571,.010064,
-.009,.010464,
-.008368,.010759,
-.007695,.010939,
-.007,.011,
0.0*
%
%ADD33MACRO33*%
%AMMACRO26*
4,1,40,.008,-.012,
-.008,-.012,
-.008695,-.011939,
-.009368,-.011759,
-.01,-.011464,
-.010571,-.011064,
-.011064,-.010571,
-.011464,-.01,
-.011759,-.009368,
-.011939,-.008695,
-.012,-.008,
-.012,.008,
-.011939,.008695,
-.011759,.009368,
-.011464,.01,
-.011064,.010571,
-.010571,.011064,
-.01,.011464,
-.009368,.011759,
-.008695,.011939,
-.008,.012,
.008,.012,
.008695,.011939,
.009368,.011759,
.01,.011464,
.010571,.011064,
.011064,.010571,
.011464,.01,
.011759,.009368,
.011939,.008695,
.012,.008,
.012,-.008,
.011939,-.008695,
.011759,-.009368,
.011464,-.01,
.011064,-.010571,
.010571,-.011064,
.01,-.011464,
.009368,-.011759,
.008695,-.011939,
.008,-.012,
0.0*
%
%ADD26MACRO26*%
%AMMACRO24*
4,1,40,.012,.008,
.012,-.008,
.011939,-.008695,
.011759,-.009368,
.011464,-.01,
.011064,-.010571,
.010571,-.011064,
.01,-.011464,
.009368,-.011759,
.008695,-.011939,
.008,-.012,
-.008,-.012,
-.008695,-.011939,
-.009368,-.011759,
-.01,-.011464,
-.010571,-.011064,
-.011064,-.010571,
-.011464,-.01,
-.011759,-.009368,
-.011939,-.008695,
-.012,-.008,
-.012,.008,
-.011939,.008695,
-.011759,.009368,
-.011464,.01,
-.011064,.010571,
-.010571,.011064,
-.01,.011464,
-.009368,.011759,
-.008695,.011939,
-.008,.012,
.008,.012,
.008695,.011939,
.009368,.011759,
.01,.011464,
.010571,.011064,
.011064,.010571,
.011464,.01,
.011759,.009368,
.011939,.008695,
.012,.008,
0.0*
%
%ADD24MACRO24*%
%ADD49C,.012*%
%ADD50C,.015*%
%ADD51C,.016*%
%ADD52C,.018*%
%ADD53C,.004*%
%ADD54C,.005*%
%ADD55C,.006*%
%ADD56C,.008*%
%ADD64C,.06004*%
%ADD65C,.06204*%
%ADD60C,.04404*%
%ADD62C,.04604*%
%ADD59C,.09204*%
%ADD61C,.06604*%
%ADD58C,.11004*%
%ADD63C,.12504*%
%ADD57R,.008X.008*%
G75*
%LPD*%
G75*
G36*
G01X76000Y-69400D02*
X75954Y-69354D01*
Y-854D01*
X72100Y3000D01*
X15600D01*
X15525Y3075D01*
X11375D01*
X3150Y11300D01*
Y84350D01*
X27722Y108922D01*
X27741Y108934D01*
G03X34964Y116157I-11993J19216D01*
G01X34976Y116176D01*
X40200Y121400D01*
Y143100D01*
X29300Y154000D01*
Y154100D01*
X25200Y158200D01*
Y163200D01*
X30700Y168700D01*
X37500D01*
X49300Y156900D01*
Y105600D01*
X43500Y99800D01*
Y95491D01*
G03X42743Y94272I2446J-2364D01*
G01X42728Y94230D01*
X42349Y93852D01*
X42314D01*
X41907Y93445D01*
X41837Y93438D01*
G03X41614Y93404I265J-2488D01*
G01X41595Y93400D01*
X37900D01*
X29675Y85175D01*
X29642Y85160D01*
G03X28840Y84358I658J-1460D01*
G01X28825Y84325D01*
X26002Y81502D01*
X25958D01*
X22798Y78342D01*
Y72098D01*
X18200Y67500D01*
Y22300D01*
X26400Y14100D01*
X80400D01*
X93900Y600D01*
Y-69200D01*
X93700Y-69400D01*
X91800D01*
X91600Y-69200D01*
Y-58400D01*
X91400Y-58200D01*
X90900D01*
X90700Y-58400D01*
Y-69300D01*
X90600Y-69400D01*
X88500D01*
Y-58500D01*
X88200Y-58200D01*
X87700D01*
X87500Y-58400D01*
Y-69300D01*
X87400Y-69400D01*
X85400D01*
X85300Y-69300D01*
Y-58300D01*
X85100Y-58100D01*
X84600D01*
X84400Y-58300D01*
Y-69300D01*
X84300Y-69400D01*
X82300D01*
X82200Y-69300D01*
Y-58300D01*
X82000Y-58100D01*
X81500D01*
X81300Y-58300D01*
Y-69300D01*
X81200Y-69400D01*
X79300D01*
X79100Y-69200D01*
Y-58300D01*
X78900Y-58100D01*
X78300D01*
X78100Y-58300D01*
Y-69300D01*
X78000Y-69400D01*
X76000D01*
G37*
G36*
G01X108700Y211900D02*
X95004Y198204D01*
X94969Y198189D01*
G03X93596Y196796I1031J-2389D01*
G01X90500Y193700D01*
Y180400D01*
X87000Y176900D01*
X34500D01*
X19950Y162350D01*
Y158650D01*
X17900Y156600D01*
X6800D01*
X3001Y160399D01*
Y238051D01*
G02X3937Y238987I936J0D01*
G01X105013D01*
X108700Y235300D01*
Y211900D01*
G37*
G36*
G01X104804Y-28296D02*
X106900Y-26200D01*
X112000D01*
X114500Y-28700D01*
Y-54600D01*
X112800Y-56300D01*
Y-69200D01*
X112600Y-69400D01*
X110600D01*
X110500Y-69300D01*
Y-58200D01*
X110200Y-57900D01*
X109900D01*
X109600Y-58200D01*
Y-69300D01*
X109500Y-69400D01*
X107400D01*
Y-56800D01*
X104804Y-54204D01*
Y-28296D01*
G37*
G36*
G01X65550Y19350D02*
X46050D01*
X44700Y20700D01*
Y35900D01*
X45700Y36900D01*
X65300D01*
X72900Y44500D01*
X87900D01*
X88300Y44100D01*
Y28300D01*
X87400Y27400D01*
X73600D01*
X65550Y19350D01*
G37*
G36*
G01X67839Y63600D02*
G03X67773Y63627I-866J-2024D01*
G01X66700Y64700D01*
X66398D01*
X66189Y64908D01*
X62437D01*
G03X61596Y64700I-1J-1801D01*
G01X60000D01*
Y77300D01*
X60400Y77700D01*
X65400D01*
X66400Y78700D01*
Y88400D01*
X66800Y88800D01*
X78200D01*
X80700Y86300D01*
Y68000D01*
X79166Y66466D01*
X79106Y66455D01*
G03X77779Y65759I494J-2555D01*
G01X77721Y65702D01*
X77654D01*
X75552Y63600D01*
X67839D01*
G37*
G36*
G01X90250Y20350D02*
X72250D01*
X71200Y21400D01*
Y22900D01*
X74000Y25700D01*
X90100D01*
X91450Y24350D01*
Y21550D01*
X90250Y20350D01*
G37*
G36*
G01X74800Y47200D02*
X74100Y47900D01*
Y55200D01*
X76400Y57500D01*
X87400D01*
X88898Y56002D01*
Y48098D01*
X88000Y47200D01*
X74800D01*
G37*
G36*
G01X97000Y30600D02*
X93100Y34500D01*
Y65900D01*
X86350Y72650D01*
Y78250D01*
X89700Y81600D01*
X96500D01*
X109600Y68500D01*
X136000D01*
X140700Y63800D01*
Y48300D01*
X145450Y43550D01*
X153750D01*
X154600Y42700D01*
Y32382D01*
X152818Y30600D01*
X107092D01*
G03X106908I-92J-2300D01*
G01X103092D01*
G03X102908I-92J-2300D01*
G01X97000D01*
G37*
G36*
G01X51763Y55027D02*
X51406Y55384D01*
Y57894D01*
X50600Y58700D01*
X48500D01*
X48000Y59200D01*
Y60696D01*
X48854Y61550D01*
X49850D01*
X49871Y61571D01*
X54129D01*
X54564Y62006D01*
X54764D01*
Y62206D01*
X55008Y62450D01*
Y77800D01*
X53808Y79000D01*
X50600D01*
X49500Y80100D01*
Y83300D01*
X54850Y88650D01*
X64850D01*
X65300Y88200D01*
Y80400D01*
X63900Y79000D01*
X60300D01*
X59063Y77763D01*
Y71592D01*
X58400Y70929D01*
X56974D01*
X56531Y70486D01*
Y58231D01*
X53658Y55358D01*
Y55042D01*
X53644Y55027D01*
X51763D01*
G37*
G36*
G01X41200Y41000D02*
X39000Y43200D01*
Y51200D01*
X39600Y51800D01*
X49700D01*
X51700Y53800D01*
X53900D01*
X57500Y57400D01*
Y68900D01*
X58600D01*
X58900Y68600D01*
Y62100D01*
X60000Y61000D01*
X60910D01*
X60961Y60965D01*
G03X62437Y60506I1476J2142D01*
G01X64171D01*
G03X64853Y59453I2804J1069D01*
G01X66000Y58305D01*
Y41900D01*
X65100Y41000D01*
X41200D01*
G37*
G36*
G01X53798Y102902D02*
X51500Y105200D01*
Y117600D01*
X57900Y124000D01*
X79476D01*
G03X84062Y123926I2324J1900D01*
G03X87829Y124000I1838J2374D01*
G01X97817D01*
G03X99949Y123987I1083J2800D01*
G01X99983Y124000D01*
X101100D01*
X110100Y133000D01*
Y150500D01*
X112800Y153200D01*
X117400D01*
X118162Y153962D01*
G03X119314Y158038I-1986J2762D01*
G01X119262Y158162D01*
X120100Y159000D01*
X123719D01*
G02X124002Y158317I0J-400D01*
G03X128674I2336J-2333D01*
G02X128957Y159000I283J283D01*
G01X129300D01*
X131129Y157171D01*
X131089Y157053D01*
G03X133541Y152751I3124J-1069D01*
G01X133700Y152718D01*
Y150247D01*
G02X132974Y150016I-400J0D01*
G03Y146202I-2696J-1907D01*
G02X133700Y145971I326J-231D01*
G01Y140407D01*
G02X132974Y140176I-400J0D01*
G03Y136362I-2696J-1907D01*
G02X133700Y136131I326J-231D01*
G01Y135100D01*
X131200Y132600D01*
Y131746D01*
X131183Y131708D01*
G03Y129080I3030J-1314D01*
G01X131200Y129042D01*
Y128900D01*
X123800Y121500D01*
X114900D01*
X105879Y112479D01*
X105786Y112488D01*
G03X102707Y110600I-286J-2988D01*
G01X64200D01*
X56502Y102902D01*
X53798D01*
G37*
G36*
G01X115900Y-69400D02*
X113700D01*
Y-56500D01*
X115300Y-54900D01*
Y-34100D01*
X116300Y-33100D01*
X117600D01*
X118700Y-34200D01*
Y-54800D01*
X115800Y-57700D01*
Y-67600D01*
X115900Y-67700D01*
Y-69400D01*
G37*
G36*
G01X159600Y202800D02*
Y159424D01*
G02X159052Y159053I-400J0D01*
G03Y152915I-1219J-3069D01*
G02X159600Y152544I148J-371D01*
G01Y152282D01*
X157235Y149918D01*
G02X156623Y149974I-283J283D01*
G03X155684Y145332I-2725J-1865D01*
G02X156300Y144995I216J-337D01*
G01Y142700D01*
X156898Y142102D01*
Y140719D01*
X157600Y140018D01*
Y137900D01*
X157387Y137687D01*
X157180Y137894D01*
X157188Y137987D01*
G03X153727Y134971I-3290J282D01*
G02X153989Y134289I-21J-399D01*
G01X153900Y134200D01*
Y122000D01*
X147900Y116000D01*
X135900D01*
X135000Y116900D01*
Y127184D01*
X135144Y127226D01*
G03X135589Y133396I-931J3168D01*
G02X135473Y134042I167J363D01*
G01X135702Y134271D01*
Y135184D01*
G02X136323Y135517I400J0D01*
G03Y141021I1825J2752D01*
G02X135702Y141354I-221J333D01*
G01Y145024D01*
G02X136323Y145357I400J0D01*
G03X137991Y151407I1825J2752D01*
G02X137690Y152090I-19J400D01*
G01X138000Y152400D01*
Y156600D01*
X137192Y157408D01*
G03X135637Y158963I-2979J-1424D01*
G01X133700Y160900D01*
Y169000D01*
X135000Y170300D01*
Y207184D01*
X135144Y207226D01*
G03Y213562I-931J3168D01*
G01X135000Y213604D01*
Y215788D01*
G02X135697Y216056I400J0D01*
G03Y220482I2451J2213D01*
G02X135000Y220750I-297J268D01*
G01Y225628D01*
G02X135697Y225896I400J0D01*
G03Y230322I2451J2213D01*
G02X135000Y230590I-297J268D01*
G01Y231400D01*
X138404Y234804D01*
G02X139055Y234680I284J-282D01*
G03X144510Y238228I3034J1303D01*
G02X144804Y238900I293J272D01*
G01X147247D01*
G02X147541Y238228I1J-400D01*
G03X152385I2422J-2244D01*
G02X152679Y238900I293J272D01*
G01X155117D01*
G02X155411Y238228I1J-400D01*
G03X160255I2422J-2244D01*
G02X160549Y238900I293J272D01*
G01X161400D01*
X162600Y237700D01*
Y234100D01*
X159100Y230600D01*
Y230049D01*
X159064Y229997D01*
G03X159100Y226170I2709J-1888D01*
G01Y220208D01*
G03X159064Y216381I2673J-1939D01*
G01X159100Y216329D01*
Y215600D01*
X161000Y213700D01*
Y212853D01*
G02X160301Y212588I-400J0D01*
G03Y208200I-2468J-2194D01*
G02X161000Y207935I299J-265D01*
G01Y204200D01*
X159600Y202800D01*
G37*
G36*
G01X318907Y-43400D02*
G02X318517Y-42912I0J400D01*
G03X318548Y-41643I-3142J712D01*
G01X318288Y-40166D01*
G03X317703Y-38807I-3172J-560D01*
G03X317787Y-37328I-3088J917D01*
G01X317526Y-35851D01*
G03X317000Y-34574I-3172J-560D01*
G01Y8217D01*
X319735Y23735D01*
X325200Y29200D01*
Y34698D01*
X327088D01*
X360688Y1098D01*
X382612D01*
X386302Y4788D01*
Y10512D01*
X383613Y13200D01*
X385802Y15388D01*
Y23312D01*
X385762Y23352D01*
X385864Y23598D01*
X394912D01*
X406057Y34743D01*
G03X406702Y36300I-1557J1557D01*
G01Y40466D01*
X413828Y47592D01*
Y58514D01*
X427616Y72303D01*
X427704Y72300D01*
G03X430325Y74271I96J2600D01*
G01X430338Y74325D01*
X441202Y85188D01*
Y87700D01*
G03X436798I-2202J0D01*
G01Y87012D01*
X427225Y77438D01*
X427171Y77425D01*
G03X426459Y77130I629J-2525D01*
G01X426412Y77102D01*
X426188D01*
X409424Y60338D01*
Y49416D01*
X407382Y47374D01*
G02X406700Y47674I-283J283D01*
G03X404595Y45569I-2200J95D01*
G02X404895Y44887I17J-399D01*
G01X402298Y42290D01*
Y37212D01*
X393088Y28002D01*
X382602D01*
Y42688D01*
X388402Y48488D01*
Y57930D01*
X385802Y60530D01*
Y60912D01*
X383102Y63612D01*
Y65965D01*
X383335Y66198D01*
X383612D01*
X385057Y67643D01*
G03X381943Y70757I-1557J1557D01*
G01X381788Y70602D01*
X381511D01*
X378698Y67789D01*
Y61788D01*
X381486Y59000D01*
X381501Y58954D01*
G03X382043Y58061I2099J663D01*
G01X383998Y56106D01*
Y50312D01*
X378198Y44512D01*
Y28002D01*
X372012D01*
X363957Y36057D01*
G03X363852Y36155I-1554J-1560D01*
G02X363806Y36708I264J300D01*
G03X360542Y39656I-1707J1391D01*
G02X360258I-142J141D01*
G03X356858Y39307I-1558J-1556D01*
G02X356581Y39250I-167J110D01*
G03X355312Y39612I-1211J-1839D01*
G02X354902Y40010I-10J400D01*
G03X350886Y38752I-2202J-10D01*
G02X350702Y38152I-329J-227D01*
G03X349902Y34585I798J-2052D01*
G02X349718Y33924I-290J-275D01*
G03X348312Y30853I582J-2124D01*
G02X348112Y30315I-361J-172D01*
G03X351198Y28426I888J-2015D01*
G01X351193Y28515D01*
X351398Y28720D01*
X351619Y28498D01*
X351705D01*
X351765Y28413D01*
G03X356076Y31327I2135J1487D01*
G02X356239Y31908I334J220D01*
G03X356954Y35353I-939J1992D01*
G02X356965Y35893I301J264D01*
G03X357212Y36204I-1594J1519D01*
G02X357489Y36261I167J-110D01*
G03X360258Y36544I1211J1839D01*
G02X360542I142J-141D01*
G03X360648Y36445I1555J1559D01*
G02X360694Y35891I-264J-301D01*
G03X360843Y32943I1706J-1392D01*
G01X370188Y23598D01*
X379288D01*
X381398Y21488D01*
Y17212D01*
X378943Y14757D01*
G03Y11643I1557J-1557D01*
G01X381898Y8688D01*
Y6612D01*
X380788Y5502D01*
X362512D01*
X328757Y39257D01*
X331500Y42000D01*
Y44687D01*
X331602Y44788D01*
Y53488D01*
X338602Y60488D01*
Y60602D01*
X349099Y71098D01*
X359712D01*
X359913Y71300D01*
X361700D01*
X368700Y78300D01*
Y91200D01*
X376600Y99100D01*
X406300D01*
X421600Y114400D01*
X460000D01*
X468800Y105600D01*
X469000D01*
X475447Y66162D01*
X457127Y-12529D01*
G02X456356Y-12560I-390J90D01*
G03X455939Y-11717I-2957J-938D01*
G03X455828Y-7750I-2439J1917D01*
G03X456039Y-3917I-2328J2050D01*
G03X451870Y575I-2439J1917D01*
G03X447499Y-3736I-1871J-2475D01*
G03X447529Y-7700I2401J-1964D01*
G03X447399Y-11536I2371J-2001D01*
G03X451600Y-16026I2401J-1964D01*
G03X455637Y-15649I1800J2526D01*
G02X456315Y-16017I288J-277D01*
G01X451057Y-38600D01*
X409000D01*
X402900Y-32500D01*
X324900D01*
X323804Y-33596D01*
X323776Y-33611D01*
G03X322900Y-38691I1466J-2868D01*
G01Y-43000D01*
X322500Y-43400D01*
X318907D01*
G37*
G36*
G01X310300Y161700D02*
X308800Y163200D01*
X308700D01*
Y168087D01*
X310157Y169543D01*
G03Y172657I-1557J1557D01*
G01X308700Y174113D01*
Y182900D01*
X301800Y189800D01*
X301113D01*
X300512Y190402D01*
X296599D01*
X294700Y192300D01*
Y196900D01*
X301300Y203500D01*
X329700D01*
X335022Y198178D01*
G02X334747Y197496I-283J-282D01*
G03X332634Y194868I47J-2202D01*
G02X332204Y194393I-392J-77D01*
G03X331791Y194392I-201J-2193D01*
G02X331392Y194961I-37J398D01*
G03X329609Y193708I-1992J939D01*
G02X330008Y193139I37J-398D01*
G03X334160Y192626I1992J-939D01*
G02X334590Y193101I392J77D01*
G03X336996Y195247I204J2193D01*
G02X337678Y195522I400J-8D01*
G01X353050Y180150D01*
Y166750D01*
X348000Y161700D01*
X310300D01*
G37*
G36*
G01X505500Y178900D02*
X477600Y206800D01*
X465100D01*
X462248Y209652D01*
Y237668D01*
X463567Y238987D01*
X602308D01*
G02X602968Y238713I-2J-936D01*
G01X612473Y229208D01*
G02X612747Y228548I-662J-662D01*
G01Y163248D01*
G02X611811Y162312I-936J0D01*
G01X562598D01*
G03X555660Y155374I0J-6938D01*
G01Y147616D01*
G02X555046Y147278I-400J0D01*
G03Y109022I-12133J-19128D01*
G02X555660Y108684I214J-338D01*
G01Y9713D01*
X549339Y3392D01*
X541012D01*
X537000Y-620D01*
Y-54900D01*
X535781Y-56119D01*
X529096D01*
X527726Y-54749D01*
Y-45314D01*
X519398Y-36986D01*
X518622Y-31576D01*
X518701Y-8693D01*
X519655Y-2701D01*
X524108Y18809D01*
Y30210D01*
X520787Y71012D01*
X517349Y100657D01*
G02X517770Y101102I397J46D01*
G03X517202Y105389I130J2198D01*
G02X516680Y105710I-126J379D01*
G01X514634Y119760D01*
G02X513416Y127984I28279J8390D01*
G01X506220Y135180D01*
X505500Y139261D01*
Y178900D01*
G37*
%LPC*%
G75*
G36*
G01X65481Y215130D02*
G03X66019I269J296D01*
G02Y211870I1481J-1630D01*
G03X65481I-269J-296D01*
G02Y215130I-1481J1630D01*
G37*
G36*
G01X37217Y214486D02*
G03X37229Y215091I-255J308D01*
G02X41559Y219526I2071J2310D01*
G03X42141I291J274D01*
G02X46386Y215017I2259J-2126D01*
G03X46363Y214423I256J-307D01*
G02X42029Y209984I-2163J-2223D01*
G03X41458Y209973I-280J-285D01*
G02X37217Y214486I-2258J2127D01*
G37*
G36*
G01X74163Y201000D02*
G03X73880Y200977I-130J-152D01*
G02X73628Y204076I-1680J1423D01*
G03X73911Y204099I130J152D01*
G02X77390Y203946I1680J-1423D01*
G03X78044I327J230D01*
G02Y201406I1799J-1270D01*
G03X77390I-327J-230D01*
G02X74163Y201000I-1799J1270D01*
G37*
G36*
G01X85235Y190961D02*
G03X85194Y190407I267J-298D01*
G02X81806I-1694J-1407D01*
G03X81765Y190961I-308J256D01*
G02X85235I1735J1939D01*
G37*
G36*
G01X107505Y41747D02*
G03X108067Y41717I296J269D01*
G02X107895Y38453I1533J-1717D01*
G03X107333Y38483I-296J-269D01*
G02X104138Y38607I-1533J1717D01*
G03X103576Y38622I-289J-277D01*
G02X103662Y41893I-1576J1678D01*
G03X104224Y41878I289J277D01*
G02X107505Y41747I1576J-1678D01*
G37*
G36*
G01X131573Y61841D02*
G02X131120Y63574I-2173J358D01*
G03X131827Y63759I312J250D01*
G02X132280Y62026I2173J-358D01*
G03X131573Y61841I-312J-250D01*
G37*
G36*
G01X455760Y103525D02*
G03X455221I-270J-295D01*
G02Y106777I-1485J1626D01*
G03X455760I269J295D01*
G02Y103525I1485J-1626D01*
G37*
G36*
G01X403770Y91577D02*
G03Y90923I230J-327D01*
G02X401230I-1270J-1799D01*
G03Y91577I-230J327D01*
G02X403770I1270J1799D01*
G37*
G36*
G01X453007Y90234D02*
G03Y89695I295J-270D01*
G02X449755I-1626J-1485D01*
G03Y90234I-295J270D01*
G02X453007I1626J1485D01*
G37*
G36*
G01X423687Y90601D02*
G03X424025Y90152I397J-53D01*
G02X421408Y88176I-335J-2277D01*
G03X421070Y88625I-397J53D01*
G02X420873Y88662I326J2279D01*
G03X420636Y88409I-46J-194D01*
G02X418702Y90014I-2199J-682D01*
G03X419141Y90484I46J397D01*
G02X423687Y90601I2264J418D01*
G37*
G36*
G01X373956Y83444D02*
G03X373672I-142J-141D01*
G02Y86556I-1558J1556D01*
G03X373956I142J141D01*
G02Y83444I1558J-1556D01*
G37*
G36*
G01X397296Y64596D02*
G03X397013Y64587I-137J-146D01*
G02X396915Y67696I-1607J1505D01*
G03X397198Y67705I137J146D01*
G02X397296Y64596I1607J-1505D01*
G37*
G36*
G01X351395Y65606D02*
G03X351678Y65581I154J128D01*
G02X351406Y62493I1422J-1681D01*
G03X351123Y62518I-154J-128D01*
G02X351395Y65606I-1422J1681D01*
G37*
G36*
G01X351312Y57501D02*
G03X351594Y57491I146J136D01*
G02X351486Y54381I1504J-1609D01*
G03X351204Y54391I-146J-136D01*
G02X351312Y57501I-1504J1609D01*
G37*
G36*
G01X463139Y50782D02*
G03Y50243I295J-270D01*
G02X459887I-1626J-1485D01*
G03Y50782I-295J270D01*
G02X463139I1626J1485D01*
G37*
G36*
G01X354120Y45398D02*
X352808D01*
G02X349920Y49136I-2308J1202D01*
G03X350185Y49711I-90J390D01*
G02X353760Y52219I1952J1019D01*
G03X354042Y52207I147J135D01*
G02X357027Y48969I1494J-1618D01*
G03X357016Y48686I136J-147D01*
G02X357066Y48630I-1617J-1494D01*
G03X357367Y48629I151J131D01*
G02X357483Y45603I1656J-1452D01*
G03X356926Y45605I-280J-286D01*
G02X354120Y45398I-1528J1586D01*
G37*
G36*
G01X390164Y38142D02*
G03X390655Y37834I392J79D01*
G02X389042Y35264I545J-2133D01*
G03X388551Y35572I-392J-79D01*
G02X390164Y38142I-545J2133D01*
G37*
G36*
G01X345725Y37035D02*
G03X345931Y36841I200J6D01*
G02X343799Y34576I69J-2201D01*
G03X343593Y34770I-200J-6D01*
G02X345725Y37035I-69J2201D01*
G37*
G36*
G01X423117Y21493D02*
X420365Y21466D01*
X420306Y21398D01*
G02X416448Y22804I-1656J1452D01*
G01X416444Y23000D01*
X415400D01*
X414141Y24259D01*
X412781Y22898D01*
X410797D01*
X410767Y22734D01*
G02X407330Y24923I-2167J390D01*
G03Y25577I-230J327D01*
G02X409276Y29472I1270J1799D01*
G03X409798Y29860I122J381D01*
G02X413777Y31200I2202J40D01*
G03X414383Y31153I323J236D01*
G01X416831Y33602D01*
X422369D01*
X426467Y29503D01*
X426548Y29502D01*
G02X428778Y25643I-48J-2602D01*
G03X429239Y25066I350J-193D01*
G02X428152Y21548I611J-2116D01*
G01X425370D01*
X424272Y22647D01*
X423117Y21493D01*
G37*
G36*
G01X323715Y185687D02*
G03X323852Y185439I192J-56D01*
G02X321128Y183936I-609J-2116D01*
G03X320991Y184184I-192J56D01*
G02X323715Y185687I609J2116D01*
G37*
G36*
G01X328470Y176477D02*
G03Y175823I230J-327D01*
G02X325930I-1270J-1799D01*
G03Y176477I-230J327D01*
G02X328470I1270J1799D01*
G37*
G36*
G01X529383Y221486D02*
G03X529977Y221463I307J256D01*
G02X529817Y217314I2223J-2163D01*
G03X529223Y217337I-307J-256D01*
G02X529383Y221486I-2223J2163D01*
G37*
G36*
G01X518682Y222574D02*
X519725Y222601D01*
G02X519834I54J-3001D01*
G02X518902Y216563I66J-3101D01*
G01X518869Y216574D01*
X518795Y216572D01*
X517532D01*
X517486Y216545D01*
G02X517217Y222593I-1686J2955D01*
G01X517257Y222574D01*
X518682D01*
G37*
G36*
G01X506769Y212715D02*
G02X502454Y208269I-2269J-2115D01*
G02X497946I-2254J2131D01*
G03X497661Y208275I-145J-137D01*
G02X493198Y212579I-2161J2225D01*
G03X493186Y213127I-297J268D01*
G02X493215Y217502I2214J2173D01*
G02X497754Y221731I2286J2097D01*
G03X498039Y221725I145J137D01*
G02X502312Y221772I2161J-2225D01*
G03X502591Y221778I136J146D01*
G02X506985Y217398I2209J-2178D01*
G02X506781Y213000I-2285J-2098D01*
G03X506769Y212715I134J-148D01*
G37*
G36*
G01X567286Y206800D02*
Y206702D01*
X567283Y206607D01*
G02Y206987I-6259J190D01*
G01X567285Y206895D01*
X567286Y206802D01*
Y206800D01*
G37*
G36*
G01Y190264D02*
Y190166D01*
X567283Y190071D01*
G02Y190451I-6259J190D01*
G01X567285Y190359D01*
X567286Y190266D01*
Y190264D01*
G37*
G36*
G01X544658Y172061D02*
X544761Y172043D01*
X546138Y173420D01*
X549678D01*
G02X550106Y173818I1700J-1399D01*
G03Y174472I-230J327D01*
G02X553568Y176479I1270J1799D01*
G01X553575Y176407D01*
X554739Y175243D01*
X554842Y175261D01*
G02X553650Y170688I458J-2561D01*
G03X553086Y170631I-254J-309D01*
G02X549678Y170618I-1709J1388D01*
G01X547300D01*
X546743Y170061D01*
X546761Y169958D01*
G02X544658Y172061I-2561J-458D01*
G37*
G36*
G01X520491Y157159D02*
X520482Y157066D01*
X520877Y156670D01*
X520937Y156658D01*
G02X518342Y154063I-437J-2158D01*
G01X518330Y154123D01*
X517642Y154810D01*
X517574Y154818D01*
G02X520491Y157159I326J2582D01*
G37*
G54D64*
X520970Y192569D03*
G54D65*
X540500Y219500D03*
G54D60*
X56500Y202900D03*
X100500Y209300D03*
X98300Y72000D03*
X104500Y56200D03*
X117200Y65750D03*
X116900Y59450D03*
X132600Y39900D03*
X137900Y49400D03*
X337900Y46800D03*
X409400Y69800D03*
X423500Y37800D03*
X372400Y41100D03*
X433900Y11000D03*
X438900Y13400D03*
X428600Y16900D03*
X435287Y25646D03*
X441688Y74914D03*
X449400Y26433D03*
X454000Y40600D03*
X348200Y169900D03*
X524994Y-38000D03*
X530994D03*
X525000Y158000D03*
X528500Y200000D03*
G54D62*
X428500Y107700D03*
X424200Y103800D03*
X432100D03*
G54D59*
X40794Y230682D03*
X540347Y32747D03*
X599868Y229462D03*
G54D61*
X122403Y148109D03*
Y138269D03*
X126338Y130394D03*
X142088Y155984D03*
X146023Y148109D03*
X149963Y155984D03*
X142088Y130394D03*
X146023Y138269D03*
X149963Y130394D03*
X146023Y228109D03*
X153898D03*
X142088Y210394D03*
X146023Y218269D03*
X149963Y210394D03*
X153898Y218269D03*
G54D58*
X14794Y226306D03*
X542107Y17432D03*
X585785Y228866D03*
G54D63*
X539370Y190256D03*
Y206792D03*
G54D57*
X41000Y95500D03*
X69100Y67400D03*
X72500D03*
X53767Y57382D03*
X42600Y47800D03*
%LPD*%
G75*
G54D10*
G01X24400Y65600D02*
Y69700D01*
X25300Y70600D01*
Y77306D01*
X26994Y79000D01*
X31150D01*
G01X32650Y67300D02*
Y71000D01*
X32300Y71350D01*
G01X36800Y59750D02*
X34550D01*
X30900Y63400D01*
G01X32650Y67300D02*
Y65150D01*
X30900Y63400D01*
G01X32300Y71350D02*
X29550D01*
X28000Y69800D01*
G01X48326Y74524D02*
X45550Y77300D01*
X42000D01*
X39550Y79750D01*
Y80700D01*
G01X39000Y85200D02*
Y87850D01*
X42100Y90950D01*
G01X39550Y80700D02*
Y84650D01*
X39000Y85200D01*
G01X45946Y93127D02*
X45162D01*
X43385Y91350D01*
X43350D01*
X42950Y90950D01*
X42100D01*
G01X36150Y67300D02*
X37450Y66000D01*
X39300D01*
X39700Y66400D01*
G01X46300Y67200D02*
X46200Y67100D01*
X40400D01*
X39700Y66400D01*
G01X31150Y82900D02*
Y79000D01*
G01X44500Y64500D02*
X44400D01*
X43150Y63250D01*
X36800D01*
G01X44500Y74250D02*
X44250Y74000D01*
X42295D01*
X41500Y74795D01*
X36192Y79000D01*
X34650D01*
G01Y82900D02*
Y79000D01*
G01X32300Y74850D02*
X28250D01*
X27800Y75300D01*
G01X32300Y74850D02*
X32750D01*
X36250Y71350D01*
X36500D01*
G01D02*
X38050D01*
X40700Y68700D01*
X44800D01*
X21800Y-41500D03*
X14794Y226306D03*
X168268Y143189D03*
Y223189D03*
X456258Y143189D03*
Y223189D03*
X542107Y17432D03*
X585785Y228866D03*
X610300Y-43600D03*
X612500Y540800D03*
G54D11*
X24400Y65400D03*
X70800Y65700D03*
G54D20*
X40900Y55100D03*
G54D30*
X36800Y59800D03*
X44500Y70800D03*
X42100Y91000D03*
G54D21*
X62700Y85600D03*
X70300D03*
G54D12*
X24400Y59800D03*
X70800Y60100D03*
G54D40*
X51563Y76493D03*
X62437Y63107D03*
G54D22*
X32300Y74900D03*
G54D13*
G01X95906Y-65409D02*
Y-53300D01*
G01X126800Y-53409D02*
Y-54476D01*
X127402Y-55078D01*
Y-65409D01*
G01X154080Y-53409D02*
X155748Y-55077D01*
Y-65409D01*
G01X163529Y-53409D02*
X165197Y-55077D01*
Y-65409D01*
G01X172977Y-53409D02*
X174645Y-55077D01*
Y-58702D01*
X174646Y-58703D01*
Y-65409D01*
G01X135182Y-53409D02*
X136851Y-55078D01*
Y-65409D01*
G01X144631Y-53409D02*
X146300Y-55078D01*
Y-65409D01*
G01X201324Y-53409D02*
X202992Y-55077D01*
Y-65409D01*
G01X210773Y-53409D02*
X212441Y-55077D01*
Y-65409D01*
G01X258017Y-53409D02*
X259685Y-55077D01*
Y-65409D01*
G01X191875Y-53409D02*
X193544Y-55078D01*
Y-65409D01*
G01X220221Y-53409D02*
X221890Y-55078D01*
Y-65409D01*
G01X229670Y-53409D02*
X231339Y-55078D01*
Y-65409D01*
G01X248568Y-53409D02*
X250237Y-55078D01*
Y-65409D01*
G01X239119Y-53409D02*
X240788Y-56300D01*
Y-65409D01*
G01X267466Y-53409D02*
X269134Y-55077D01*
Y-65409D01*
G01X305261Y-53409D02*
X306929Y-55077D01*
Y-65409D01*
G01X314710Y-53409D02*
X316378Y-55077D01*
Y-65409D01*
G01X343056Y-53409D02*
X344724Y-55077D01*
Y-58702D01*
X344725Y-58703D01*
Y-65409D01*
G01X276914Y-53409D02*
X278583Y-55078D01*
Y-65409D01*
G01X286363Y-53409D02*
X288032Y-55078D01*
Y-65409D01*
G01X295812Y-53409D02*
X297481Y-55078D01*
Y-65409D01*
G01X324158Y-53409D02*
X325827Y-55078D01*
Y-65409D01*
G01X333607Y-53409D02*
X335276Y-55078D01*
Y-65409D01*
G01X352505Y-53409D02*
X354173Y-55077D01*
Y-58702D01*
X354174Y-58703D01*
Y-65409D01*
G01X361954Y-53409D02*
X363622Y-55077D01*
Y-65409D01*
G01X371403Y-53409D02*
X373071Y-55077D01*
Y-65409D01*
G01X390300Y-53409D02*
X391968Y-55077D01*
Y-58702D01*
X391969Y-58703D01*
Y-65409D01*
G01X399815Y-52741D02*
X401418Y-54344D01*
Y-65409D01*
G01X380851Y-53409D02*
X382520Y-55078D01*
Y-65409D01*
G01X455701Y-53425D02*
X457303Y-55027D01*
Y-65809D01*
G01X502945Y-53425D02*
X504547Y-55027D01*
Y-65809D01*
G01X493496Y-53425D02*
X495098Y-55027D01*
Y-65809D01*
G01X484047Y-53425D02*
X485650Y-55028D01*
Y-65809D01*
G01X474598Y-53425D02*
X476201Y-55028D01*
Y-65809D01*
G01X465149Y-53425D02*
X466752Y-55028D01*
Y-65809D01*
G01X446252Y-53425D02*
X447854Y-55027D01*
Y-65809D01*
G01X523445D02*
Y-55028D01*
X521842Y-53425D01*
G01X512393D02*
X513996Y-55028D01*
Y-65809D01*
G01X532894D02*
Y-55028D01*
G01D02*
X531291Y-53425D01*
X25700Y89200D03*
X27207Y85293D03*
X24400Y81900D03*
X22300Y85000D03*
X21800Y78600D03*
X21600Y74000D03*
X28200Y160400D03*
X95906Y-53300D03*
X84619Y-27663D03*
X89467Y-47981D03*
X84671Y-44973D03*
X79444Y-46817D03*
X90546Y-41425D03*
X90332Y-30191D03*
X85442Y-39927D03*
X79444Y-41282D03*
X90400Y-36500D03*
X85231Y-34026D03*
X79035Y-30696D03*
X79103Y-35748D03*
X107800Y4300D03*
X107000Y-49000D03*
X106800Y-53000D03*
X107100Y-36900D03*
X107500Y-33200D03*
X76300Y79700D03*
X78900Y82400D03*
X78200Y76200D03*
X78300Y72600D03*
X78400Y68900D03*
X74700Y73100D03*
X73500Y76600D03*
X74900Y65800D03*
X74800Y69500D03*
X71000Y73500D03*
X67400Y76200D03*
X71100Y69800D03*
X67200Y72400D03*
Y68800D03*
X83400Y55300D03*
X72400Y22300D03*
X90100Y23100D03*
X64200Y99200D03*
X78000Y99900D03*
X87300Y55300D03*
X75500Y55400D03*
X79099Y55280D03*
X33200Y98700D03*
X30600Y88100D03*
X33700Y91400D03*
X29400Y92300D03*
X32800Y95000D03*
X102000Y40300D03*
X103000Y28300D03*
X105800Y40200D03*
X107000Y28300D03*
X96000Y80100D03*
X97800Y76800D03*
X93000Y73300D03*
X93800Y77000D03*
X89800Y76700D03*
X50700Y81900D03*
X58000Y81600D03*
X53000Y59800D03*
X49400Y60000D03*
X54300Y81700D03*
X71500Y39500D03*
X71700Y31500D03*
X69300Y36500D03*
X69400Y26700D03*
X86000Y36087D03*
X78600Y36200D03*
X74600Y36100D03*
X82300Y36200D03*
X64600Y104500D03*
X78000Y105800D03*
X32400Y160600D03*
X29200Y164000D03*
X33100Y164800D03*
X36000Y161800D03*
X31000Y156900D03*
X55600Y105100D03*
X54400Y110000D03*
X54600Y114900D03*
X59000Y107900D03*
X59700Y115200D03*
X44200Y212200D03*
X39200Y212100D03*
X44400Y217400D03*
X39300D03*
X111600Y4100D03*
X115500Y4000D03*
X119300Y3800D03*
X123000D03*
X127000Y3900D03*
X130800Y4000D03*
X111300Y-49100D03*
X111100Y-53100D03*
X111400Y-37000D03*
X111800Y-33300D03*
X131266Y85081D03*
X135025Y85092D03*
X138722Y85144D03*
X131666Y78581D03*
X135425Y78592D03*
X139122Y78644D03*
X109600Y40000D03*
X110800Y28100D03*
X138922Y94844D03*
X135225Y94792D03*
X131466Y94781D03*
X172300Y94300D03*
X169800Y91100D03*
X174900Y90900D03*
X152700Y33300D03*
X152279Y36876D03*
X153000Y40700D03*
X167100Y181200D03*
X163300Y178900D03*
X135100Y161900D03*
X155600Y166300D03*
X151700D03*
X134900Y165700D03*
X146165Y120044D03*
X140552Y117907D03*
X136626Y118116D03*
X158100Y116300D03*
X158000Y120900D03*
Y124800D03*
X142500Y203900D03*
X145300Y201100D03*
X148314Y203751D03*
X162100Y193800D03*
X165700Y195000D03*
X363700Y78200D03*
X421405Y90902D03*
X418437Y87727D03*
X423690Y87875D03*
X428500Y107700D03*
X424200Y103800D03*
X453500Y-9800D03*
X449900Y-9700D03*
X453400Y-13500D03*
X449800D03*
X453500Y-5700D03*
X449900D03*
X453600Y-2000D03*
X450000Y-1900D03*
X460535Y76560D03*
X456662Y76376D03*
X432100Y103800D03*
X495500Y219600D03*
Y210500D03*
X495400Y215300D03*
X500200Y219500D03*
X504800Y219600D03*
X504500Y210600D03*
X500200Y210400D03*
X504700Y215300D03*
X500100Y215200D03*
X540500Y219500D03*
X532200Y219300D03*
X527000Y219500D03*
X519900D03*
G54D31*
X36800Y63200D03*
X44500Y74200D03*
X42100Y94400D03*
G54D50*
G01X30700Y56400D02*
X30900Y56600D01*
Y59200D01*
G01X87900Y94500D02*
X110669Y71731D01*
X145431D01*
X147500Y73800D01*
X147900D01*
G54D32*
X43000Y80700D03*
G54D23*
X32300Y71300D03*
G54D14*
X28000Y69800D03*
X26400Y42900D03*
X27800Y75300D03*
X84100Y-19500D03*
X106900Y15700D03*
X102700Y2000D03*
X98200Y6200D03*
X91363Y12538D03*
X76600Y85700D03*
X93200Y69100D03*
X90300Y59600D03*
X45946Y93127D03*
X39700Y66400D03*
X51600Y89900D03*
X55300Y86600D03*
X44500Y64500D03*
X79600Y63900D03*
X36847Y157992D03*
X55500Y168400D03*
X95800Y175700D03*
X105400Y168500D03*
X71500Y172300D03*
X43400Y191700D03*
X83500Y192900D03*
X96000Y195800D03*
X156600Y4900D03*
X126517Y-4483D03*
X109300Y-28000D03*
X125000Y36300D03*
X173600Y39200D03*
X161400Y62500D03*
X154300Y60200D03*
X120200Y78900D03*
X113600Y90100D03*
X108200Y100300D03*
X118800Y94600D03*
X173800Y171200D03*
X113600Y164600D03*
X168800Y169600D03*
X153700Y182800D03*
X184500Y184800D03*
X183900Y189900D03*
X181600Y194800D03*
X187400Y195900D03*
X169200Y188000D03*
X238400Y89300D03*
X221400Y179200D03*
X203700Y194000D03*
X260700Y197900D03*
X246200Y193600D03*
X209800Y183700D03*
X342100Y179200D03*
X274479Y167895D03*
X293300Y188200D03*
X426600Y-20400D03*
X427800Y74900D03*
X351300Y82000D03*
X353900Y29900D03*
X350500Y46600D03*
X426500Y26900D03*
X417700Y27800D03*
X507600Y204400D03*
X523000Y68700D03*
X524200Y167800D03*
X517900Y157400D03*
X555300Y172700D03*
X544200Y169500D03*
X515800Y219500D03*
X589800Y200900D03*
G54D41*
X51563Y74524D03*
Y72950D03*
Y71375D03*
Y69800D03*
Y68225D03*
Y66650D03*
Y65076D03*
G54D51*
G01X45800Y54800D02*
X47150Y56150D01*
X48985D01*
X49017Y56182D01*
G54D24*
X34700Y82900D03*
X52567Y56182D03*
G54D33*
X39600Y80700D03*
G54D42*
X30900Y62550D03*
G54D15*
X15748Y128150D03*
X542913D03*
G54D52*
G01X43050Y80700D02*
Y81850D01*
X45000Y83800D01*
Y85200D01*
G54D25*
X31100Y82900D03*
X48967Y56182D03*
G54D43*
X30900Y60050D03*
G54D34*
X44800Y85200D03*
G54D16*
G01X-84798Y-164972D02*
Y-244972D01*
G01D02*
X1172402D01*
G01X-88798Y-148972D02*
G02I-12000J0D01*
G01X-93948D02*
G02I-6850J0D01*
G01X-100798Y-164972D02*
Y-132972D01*
G01X-84798Y-148972D02*
X-116798D01*
G01X-84798Y-164972D02*
X1172402D01*
G01X-84798Y-200472D02*
X1172402D01*
G01X45200Y89400D02*
Y85400D01*
X45000Y85200D01*
G01X44500Y70750D02*
X41950D01*
X39900Y72800D01*
G01D02*
X37850Y74850D01*
X36500D01*
G01X42600Y102200D02*
X44900Y99900D01*
X55800D01*
X63300Y92400D01*
X84800D01*
X86900Y94500D01*
X87900D01*
G01X40900Y55300D02*
X41046D01*
X45046Y59300D01*
G01X70800Y59900D02*
X68650D01*
X66975Y61575D01*
G01X75250Y60000D02*
X75150Y59900D01*
X70800D01*
G01X125000Y93400D02*
X111800Y106600D01*
Y113700D01*
G01X130278Y134767D02*
Y138269D01*
G01D02*
Y141771D01*
G01X126776Y138269D02*
X130278D01*
G01X126338Y126892D02*
Y130394D01*
G01D02*
Y133896D01*
G01X122836Y130394D02*
X126338D01*
G01D02*
X129840D01*
G01X122403Y134767D02*
Y138269D01*
G01D02*
Y141771D01*
G01X118901Y138269D02*
X122403D01*
G01D02*
X125905D01*
G01X130278Y144607D02*
Y148109D01*
G01D02*
Y151611D01*
G01X126776Y148109D02*
X130278D01*
G01X126338Y152482D02*
Y155984D01*
G01D02*
X129840D01*
G01X149963Y126892D02*
Y130394D01*
G01D02*
Y133896D01*
G01X146461Y130394D02*
X149963D01*
G01D02*
X153465D01*
G01X157833Y152482D02*
Y155984D01*
G01D02*
Y159486D01*
G01X154331Y155984D02*
X157833D01*
G01X153898Y144607D02*
Y148109D01*
G01D02*
Y151611D01*
G01X150396Y148109D02*
X153898D01*
G01X149963Y206892D02*
Y210394D01*
G01D02*
Y213896D01*
G01X146461Y210394D02*
X149963D01*
G01D02*
X153465D01*
G01X157833Y232482D02*
Y235984D01*
G01X154331D02*
X157833D01*
G01D02*
X161335D01*
G01X153898Y224607D02*
Y228109D01*
G01D02*
Y231611D01*
G01X150396Y228109D02*
X153898D01*
G01D02*
X157400D01*
G01X203700Y194000D02*
X203300D01*
X194900Y185600D01*
X191600D01*
G01X209400Y200100D02*
X211400D01*
X225600Y185900D01*
G01D02*
Y186500D01*
X230500Y191400D01*
G01X209400Y200100D02*
Y199700D01*
X203700Y194000D01*
G01X380200Y3300D02*
X361600D01*
X328000Y36900D01*
X324600D01*
G01D02*
Y40900D01*
X329400Y45700D01*
Y50300D01*
G01X363700Y78200D02*
X358800Y73300D01*
X339100D01*
G01X329400Y50300D02*
Y54400D01*
X336400Y61400D01*
Y70600D01*
X339100Y73300D01*
G01X308600Y171100D02*
X299600Y162100D01*
X289600D01*
G01X301500Y186300D02*
X303750Y184050D01*
Y175950D01*
X308600Y171100D01*
G01X294600Y201300D02*
X291800Y198500D01*
Y189700D01*
X293300Y188200D01*
G01X301500Y186300D02*
X299600Y188200D01*
X293300D01*
G01X384902Y-164972D02*
Y-244972D01*
G01X380500Y13200D02*
X383600Y16300D01*
Y22400D01*
X380200Y25800D01*
G01X380500Y13200D02*
X384100Y9600D01*
Y5700D01*
X381700Y3300D01*
X380200D01*
G01X383600Y59618D02*
Y60000D01*
X380900Y62700D01*
Y66877D01*
X382423Y68400D01*
X382700D01*
X383500Y69200D01*
G01X380200Y25800D02*
X394000D01*
X404500Y36300D01*
G01X383600Y59618D02*
X386200Y57018D01*
Y49400D01*
X383400Y46600D01*
G01X362400Y34500D02*
X371100Y25800D01*
X380200D01*
G01X427800Y74900D02*
X427100D01*
X411626Y59426D01*
Y48504D01*
X404500Y41378D01*
Y36300D01*
G01X439000Y87700D02*
Y86100D01*
X427800Y74900D01*
G01X383400Y46600D02*
X380400Y43600D01*
Y26000D01*
X380200Y25800D01*
G01X522402Y-164972D02*
Y-244972D01*
G01X515800Y219500D02*
X515873Y219573D01*
X518720D01*
X519800Y219600D01*
X519900Y219500D01*
G01X637402Y-164972D02*
Y-244972D01*
G01X804902Y-164972D02*
Y-244972D01*
G01X974902Y-164972D02*
Y-244972D01*
G01X1172402Y-164972D02*
Y-244972D01*
G01X1200402Y-148972D02*
G02I-12000J0D01*
G01X1195252D02*
G02I-6850J0D01*
G01X1188402Y-164972D02*
Y-132972D01*
G01X1204402Y-148972D02*
X1172402D01*
X6487Y175762D03*
Y165762D03*
X14947Y175971D03*
Y165971D03*
X22700Y190800D03*
X26300D03*
X26600Y201000D03*
X23000D03*
X6487Y235762D03*
X25453Y235870D03*
X15453D03*
X6487Y225762D03*
Y215762D03*
Y205762D03*
Y195762D03*
Y185762D03*
X14947Y195971D03*
Y185971D03*
X92940Y6625D03*
X99000Y13800D03*
X99200Y18100D03*
X107400Y11300D03*
X98200Y10000D03*
X94042Y9842D03*
X93900Y95300D03*
X104600Y95000D03*
X102400Y92600D03*
X106800Y92700D03*
X104600Y90500D03*
X45800Y54800D03*
X45200Y89400D03*
X30700Y56400D03*
X98300Y72000D03*
X39900Y72800D03*
X87900Y94500D03*
X87250Y100650D03*
X98300Y67500D03*
X104500Y56200D03*
X88000Y65200D03*
X83200Y60000D03*
X48800Y87100D03*
X62000Y142900D03*
X56300Y180000D03*
X101500Y135908D03*
X62700Y150100D03*
X69000Y143300D03*
X79000Y142500D03*
X77000Y140300D03*
X81300Y140400D03*
X79200Y138100D03*
X104743Y174953D03*
X98900Y126800D03*
X85700Y129900D03*
X85900Y126300D03*
X81700Y129700D03*
X81800Y125900D03*
X68800Y139000D03*
X59400Y151000D03*
X56400Y164250D03*
X67750Y160700D03*
X66100Y151000D03*
X98900Y172350D03*
X92400Y163100D03*
X80000Y158900D03*
X80400Y167200D03*
X102202Y131798D03*
X101500Y139900D03*
X100000Y175700D03*
X105500Y109500D03*
X105400Y153600D03*
X106500Y149000D03*
X105218Y137218D03*
X71500Y168500D03*
X100800Y189700D03*
X100700Y182900D03*
X98400Y233100D03*
X59600Y214000D03*
X100700Y186300D03*
X35453Y235870D03*
X45453D03*
X55453D03*
X65453D03*
X75453D03*
X84400Y232900D03*
X89600D03*
X94900Y233000D03*
X56500Y202900D03*
X100500Y209300D03*
X75591Y202676D03*
X79843D03*
X83500Y189000D03*
X96000Y192000D03*
X72200Y202400D03*
X67500Y213500D03*
X64000D03*
X161100Y13600D03*
X126800Y-53409D03*
X135182D03*
X144631D03*
X154080D03*
X163529D03*
X172977D03*
X116900Y-35400D03*
X121801Y16999D03*
X146600Y3400D03*
X159450Y8750D03*
X160400Y4900D03*
X111018Y11382D03*
X148300Y16700D03*
X147878Y13326D03*
X182000Y66700D03*
X174400Y32500D03*
X176300Y45200D03*
X159450Y97400D03*
X151150Y83500D03*
X124900Y88900D03*
X161800Y71100D03*
X117200Y65750D03*
X116900Y59450D03*
X134000Y63400D03*
X151550Y87500D03*
X132600Y39900D03*
X147900Y73800D03*
X153300Y22300D03*
X137400Y61900D03*
X125000Y93400D03*
X129400Y62200D03*
X169800Y39200D03*
X161400Y58700D03*
X154300Y56400D03*
X124100Y78900D03*
X137900Y49400D03*
X110781Y87200D03*
X111750Y98450D03*
X152900Y46500D03*
X114850Y95650D03*
X181700Y72700D03*
X161694Y55106D03*
X154300Y49600D03*
X156600Y109800D03*
X152650D03*
X148950Y109600D03*
X116100Y169700D03*
X120400Y169800D03*
X125300Y170200D03*
X111800Y113700D03*
X117600Y117700D03*
X116176Y156724D03*
X109500Y168752D03*
X180076Y179876D03*
X175600Y166800D03*
X121700Y117300D03*
X111924Y156724D03*
X109500Y164500D03*
X172000Y166800D03*
X124400Y103100D03*
X181400Y124500D03*
X172300Y192800D03*
X164200Y205100D03*
X180300Y187200D03*
X179900Y191300D03*
X180000Y198500D03*
Y183500D03*
X183683Y198517D03*
X173300Y204969D03*
X240100Y20900D03*
X221900Y5100D03*
X235600Y5300D03*
X247200Y5400D03*
X195200Y5700D03*
X191875Y-53409D03*
X201324D03*
X210773D03*
X220221D03*
X229670D03*
X239119D03*
X248568D03*
X258017D03*
X267466D03*
X252300Y22200D03*
X255900Y35000D03*
X246500Y47900D03*
X200500Y31500D03*
X216300Y46700D03*
X226600Y21400D03*
X198300Y73200D03*
X196400Y91600D03*
X193900Y51600D03*
X202800Y50200D03*
X218900Y65600D03*
X198900Y21200D03*
X230300Y45100D03*
X233800Y66000D03*
X199400Y81400D03*
X236900Y85800D03*
X233700Y54400D03*
X262400Y169900D03*
X202300Y165100D03*
X196850Y177950D03*
X246800Y112500D03*
X198300Y111700D03*
X188900Y173300D03*
X225100Y168100D03*
X199900Y161600D03*
X192200Y166700D03*
X195900Y162100D03*
X242800Y200600D03*
X243000Y185300D03*
X239400Y191500D03*
X191600Y185600D03*
X209400Y200100D03*
X225600Y185900D03*
X230500Y191400D03*
X224100Y200100D03*
X256747Y199700D03*
X250100Y193000D03*
X267500Y182000D03*
X266000Y185100D03*
X254900Y188300D03*
X345042Y-41479D03*
X339942D03*
X324642D03*
X334842D03*
X329742D03*
X319070Y-41541D03*
X276914Y-53409D03*
X286363D03*
X295812D03*
X305261D03*
X314710D03*
X324158D03*
X333607D03*
X343056D03*
X324021Y-46464D03*
X334221D03*
X344421D03*
X320021D03*
X330221D03*
X340421D03*
X329242Y-36479D03*
X339442D03*
X325242D03*
X335442D03*
X345642D03*
X328000Y30500D03*
Y59000D03*
X339649Y41539D03*
X329400Y50300D03*
X339100Y73300D03*
X324600Y36900D03*
X343524Y36971D03*
X346000Y34640D03*
X300800Y100100D03*
X337900Y46800D03*
X346150Y84800D03*
X328655Y170950D03*
X313400Y119100D03*
X289600Y162100D03*
X308600Y171100D03*
X274400Y161700D03*
X327200Y178276D03*
Y174024D03*
X348200Y169900D03*
X326600Y182000D03*
X295800Y195900D03*
X294600Y201300D03*
X301500Y186300D03*
X332000Y192200D03*
X329400Y195900D03*
X334794Y195294D03*
X321600Y186300D03*
X323243Y183323D03*
X396042Y-41479D03*
X390942D03*
X380742D03*
X385842D03*
X375642D03*
X370542D03*
X365442D03*
X360342D03*
X355242D03*
X401142D03*
X350142D03*
X423852Y4375D03*
X420252Y-36925D03*
X410052Y-36825D03*
X380500Y17100D03*
X352505Y-53409D03*
X361954D03*
X371403D03*
X380851D03*
X390300D03*
X399815Y-52741D03*
X415100Y3400D03*
X352600Y7600D03*
X380200Y6800D03*
X380500Y13200D03*
X380200Y3300D03*
X354621Y-46464D03*
X364821D03*
X375021D03*
X385221D03*
X395421D03*
X350621D03*
X360821D03*
X371021D03*
X381221D03*
X391421D03*
X349642Y-36479D03*
X359842D03*
X370042D03*
X380242D03*
X390442D03*
X400642D03*
X355842D03*
X366042D03*
X376242D03*
X386442D03*
X396642D03*
X405500Y29200D03*
X370400Y88200D03*
X377800Y87800D03*
X383300Y50700D03*
X383500Y65800D03*
X388000Y41600D03*
X394500Y34000D03*
X380300Y21600D03*
X405800Y21100D03*
Y94200D03*
X405600Y87500D03*
X420322Y56072D03*
X423202Y56119D03*
X426128Y50188D03*
Y53348D03*
X426065Y56213D03*
X426113Y59046D03*
X425971Y62050D03*
X423500Y34200D03*
X416300Y37100D03*
X418705Y34695D03*
X405569Y72731D03*
X409026Y61211D03*
X383600Y55532D03*
X401211Y46589D03*
X373300Y35400D03*
X384000Y41600D03*
X391600Y29400D03*
X361600Y69100D03*
X383500Y69200D03*
X383600Y59618D03*
X383400Y46600D03*
X362400Y34500D03*
X404500Y36300D03*
X380200Y25800D03*
X349701Y64199D03*
X353100Y63900D03*
X359023Y47177D03*
X355370Y37411D03*
X355300Y81400D03*
X349700Y56000D03*
X349000Y28300D03*
X404500Y47769D03*
X409400Y69800D03*
X423500Y37800D03*
X412000Y29900D03*
X356700Y86600D03*
X353098Y55882D03*
X350300Y31800D03*
X352138Y50729D03*
X351500Y36100D03*
X355536Y50589D03*
X352700Y40000D03*
X355399Y47191D03*
X355300Y33900D03*
X391200Y35700D03*
X398805Y66200D03*
X408600Y27376D03*
X388006Y37706D03*
X395406Y66092D03*
X418650Y22850D03*
X408600Y23124D03*
X402500Y89124D03*
X375514Y85000D03*
X402500Y93376D03*
X372114Y85000D03*
X358700Y38100D03*
X362100D03*
X372400Y41100D03*
X436752Y4175D03*
X498052Y-625D03*
X490200Y-6400D03*
X488652Y-18225D03*
X496352Y-19025D03*
X432452Y-36225D03*
X447252Y-47725D03*
X445252Y-37225D03*
X455701Y-53425D03*
X502945D03*
X493496D03*
X484047D03*
X474598D03*
X465149D03*
X446252D03*
X433900Y11000D03*
X438900Y13400D03*
X428600Y16900D03*
X469300Y87600D03*
X459652Y31575D03*
X458100Y47300D03*
Y53700D03*
X448200Y93000D03*
X448369Y86631D03*
X432091Y56151D03*
X429056Y56135D03*
X457400Y41800D03*
X468588Y55981D03*
X431382Y35283D03*
X437300Y91100D03*
X454085Y63272D03*
X452496Y70099D03*
X454500Y29300D03*
X439418Y26110D03*
X439000Y87700D03*
X451381Y88210D03*
Y91719D03*
X435287Y25646D03*
X441688Y74914D03*
X449400Y26433D03*
X454000Y40600D03*
X429850Y22950D03*
X461513Y48758D03*
Y52267D03*
X452888Y108444D03*
X457097Y108548D03*
X457245Y105151D03*
X453736D03*
X466361Y230936D03*
X467506Y226106D03*
X502000Y229400D03*
X466010Y216328D03*
X492961Y227336D03*
X480761Y227936D03*
X505961Y236936D03*
X488161Y236336D03*
X479761D03*
X499761D03*
X455700Y205800D03*
X528590Y-12237D03*
Y2763D03*
X532137Y7890D03*
X532691Y-17725D03*
X531600Y-31800D03*
X523300Y-32100D03*
X531291Y-53425D03*
X521842D03*
X512393D03*
X524994Y-38000D03*
X530994D03*
X534737Y40290D03*
X534337Y52790D03*
X534637Y74290D03*
Y92590D03*
X532778Y21738D03*
X512000Y158400D03*
X511900Y174400D03*
Y142700D03*
X521900Y179500D03*
X548200Y169900D03*
X548300Y178100D03*
X578337Y166890D03*
X577748Y181113D03*
X529000Y158500D03*
X521600Y158400D03*
X520500Y154500D03*
X525000Y158000D03*
X551376Y176271D03*
Y172019D03*
X517900Y103300D03*
X524200Y181600D03*
X519700Y181900D03*
X521900Y184000D03*
X545300Y236800D03*
X529500Y236400D03*
X519761Y236336D03*
X537200Y236400D03*
X559761Y236336D03*
X579761D03*
X577748Y211113D03*
X578337Y226890D03*
X577748Y191113D03*
Y201113D03*
X524000Y200000D03*
X520970Y192569D03*
X528500Y200000D03*
X593337Y166890D03*
Y176890D03*
X608337Y166890D03*
Y176890D03*
X599761Y236336D03*
X593337Y206890D03*
Y216890D03*
Y226890D03*
Y186890D03*
Y196890D03*
X608337Y206890D03*
Y216890D03*
Y226890D03*
Y186890D03*
Y196890D03*
G54D53*
G01X126517Y-4483D02*
X103402Y-27598D01*
Y-56302D01*
X105355Y-58255D01*
Y-65409D01*
G01X102205D02*
Y-57605D01*
X99400Y-54800D01*
Y-1300D01*
X102700Y2000D01*
G01X90300Y59600D02*
Y35200D01*
X101000Y24500D01*
Y4900D01*
X98200Y2100D01*
Y-56737D01*
X99055Y-57592D01*
Y-65409D01*
G01X106900Y15700D02*
Y11800D01*
X107400Y11300D01*
G01X102700Y2000D02*
X103900Y3200D01*
Y4600D01*
X110100Y10800D01*
X110436D01*
X111018Y11382D01*
G01X98200Y6200D02*
Y10000D01*
G01X91363Y12538D02*
X91500Y12401D01*
Y12384D01*
X94042Y9842D01*
G01X90300Y59600D02*
Y62900D01*
X88000Y65200D01*
G01X48800Y87100D02*
X47600Y85900D01*
Y78000D01*
X49107Y76493D01*
X51563D01*
G01X51600Y89900D02*
X48800Y87100D01*
G01X78750Y60000D02*
X83200D01*
G01X95800Y175700D02*
X100000D01*
G01X105400Y168500D02*
X109248D01*
X109500Y168752D01*
G01X71500Y172300D02*
Y168500D01*
G01X83500Y192900D02*
Y189000D01*
G01X96000Y195800D02*
Y192000D01*
G01X161694Y55106D02*
X158200Y51612D01*
Y32302D01*
X142000Y16102D01*
Y-7800D01*
X120300Y-29500D01*
Y-56500D01*
X117953Y-58847D01*
Y-65409D01*
G01X148300Y16700D02*
X150300Y14700D01*
Y-4888D01*
X124100Y-31088D01*
Y-57674D01*
X124252Y-57826D01*
Y-65409D01*
G01X147878Y13326D02*
X148400Y12804D01*
Y-4100D01*
X122200Y-30300D01*
Y-56400D01*
X121103Y-57497D01*
Y-65409D01*
G01X156600Y4900D02*
X160400D01*
G01X154300Y49600D02*
X157000Y46900D01*
Y32800D01*
X138500Y14300D01*
Y7500D01*
X126517Y-4483D01*
G01X173600Y39200D02*
X169800D01*
G01X161400Y58700D02*
Y62500D01*
G01X154300Y60200D02*
Y56400D01*
G01X120200Y78900D02*
X124100D01*
G01X113600Y90100D02*
Y90019D01*
X110781Y87200D01*
G01X108200Y100300D02*
X109900D01*
X111750Y98450D01*
G01X118800Y94600D02*
X115900D01*
X114850Y95650D01*
G01X180076Y179876D02*
X180700Y180500D01*
X221400D01*
G01X173800Y171200D02*
Y168600D01*
X175600Y166800D01*
G01X113600Y164600D02*
X109600D01*
X109500Y164500D01*
G01X168800Y169600D02*
X169200D01*
X172000Y166800D01*
G01X161773Y138269D02*
X161331D01*
X158300Y141300D01*
Y149000D01*
X165150Y155850D01*
Y171450D01*
X169200Y175500D01*
Y188000D01*
G01X184500Y184800D02*
X183700Y185600D01*
X181900D01*
X180300Y187200D01*
G01X183900Y189900D02*
X182900Y190900D01*
X180300D01*
X179900Y191300D01*
G01X180000Y198500D02*
Y197835D01*
X181600Y196235D01*
Y194800D01*
G01X180000Y183500D02*
X181100Y182400D01*
X209800D01*
G01X187400Y195900D02*
X186300D01*
X183683Y198517D01*
G01X169200Y188000D02*
X169000Y188200D01*
Y202398D01*
X167300Y204098D01*
Y212742D01*
X161773Y218269D01*
G01X238400Y89300D02*
X238300Y89200D01*
Y87200D01*
X236900Y85800D01*
G01X233700Y54400D02*
X244448Y86644D01*
Y130394D01*
G01X221400Y179200D02*
Y180500D01*
G01X244448Y210394D02*
X248307Y206535D01*
Y205339D01*
X269300Y184346D01*
Y180800D01*
X248500Y160000D01*
Y153800D01*
X252200Y150100D01*
Y136700D01*
X248000Y132500D01*
X246554D01*
X244448Y130394D01*
G01X260700Y197900D02*
X258547D01*
X256747Y199700D01*
G01X250100Y193000D02*
X249900Y193200D01*
X246800D01*
X246400Y193600D01*
X246200D01*
G01X267500Y182000D02*
X263187D01*
X261687Y180500D01*
X221400D01*
G01X266000Y185100D02*
X263662D01*
X263590Y185028D01*
X263586Y185025D01*
X263581Y185021D01*
X263518Y184968D01*
X263215Y184716D01*
X260899Y182400D01*
X209800D01*
G01Y183700D02*
Y182400D01*
G01X274400Y161700D02*
X274700Y162000D01*
Y167674D01*
X274479Y167895D01*
G01X351300Y82000D02*
X351400Y82100D01*
X354600D01*
X355300Y81400D01*
G01X353900Y29900D02*
X352200D01*
X350300Y31800D01*
G01X350500Y46600D02*
X350700Y46800D01*
X355008D01*
X355399Y47191D01*
G01X408600Y27376D02*
X409776Y26200D01*
X411412D01*
X417412Y32200D01*
X421788D01*
X425185Y28803D01*
Y26900D01*
G01X429850Y22950D02*
X425951D01*
X425192Y23709D01*
X425185Y24487D01*
Y26900D01*
G01X426500D02*
X425185D01*
G01X418650Y22850D02*
X422531Y22889D01*
X423292Y23650D01*
X423285Y24478D01*
Y28015D01*
X421000Y30300D01*
X418200D01*
X416650Y28750D01*
G01D02*
X417700Y27800D01*
G01X408600Y23124D02*
X409776Y24300D01*
X412200D01*
X416650Y28750D01*
G01X555300Y172700D02*
X551729Y176271D01*
X551376D01*
G01X544200Y169500D02*
X546719Y172019D01*
X551376D01*
G54D26*
X36500Y71300D03*
G54D44*
X85100Y30700D03*
Y23100D03*
Y41900D03*
Y49500D03*
X77400Y41900D03*
Y49500D03*
Y30700D03*
Y23100D03*
G54D35*
X39200Y85200D03*
G54D17*
X105355Y-63909D03*
X102205D03*
X99055D03*
X95906D03*
X92756D03*
X89607D03*
X86457D03*
X83307D03*
X80158D03*
X77008D03*
X174646D03*
X171496D03*
X168347D03*
X165197D03*
X162048D03*
X158898D03*
X155748D03*
X152599D03*
X149449D03*
X146300D03*
X143150D03*
X140000D03*
X136851D03*
X133701D03*
X130551D03*
X127402D03*
X124252D03*
X121103D03*
X117953D03*
X114803D03*
X111654D03*
X108504D03*
X265985D03*
X262835D03*
X259685D03*
X256536D03*
X253386D03*
X250237D03*
X247087D03*
X243937D03*
X240788D03*
X237638D03*
X234489D03*
X231339D03*
X228189D03*
X225040D03*
X221890D03*
X218740D03*
X215591D03*
X212441D03*
X209292D03*
X206142D03*
X202992D03*
X199843D03*
X196693D03*
X193544D03*
X190394D03*
X347874D03*
X344725D03*
X341575D03*
X338426D03*
X335276D03*
X332126D03*
X328977D03*
X325827D03*
X322677D03*
X319528D03*
X316378D03*
X313229D03*
X310079D03*
X306929D03*
X303780D03*
X300630D03*
X297481D03*
X294331D03*
X291181D03*
X288032D03*
X284882D03*
X281733D03*
X278583D03*
X275433D03*
X272284D03*
X269134D03*
X401418D03*
X398268D03*
X395118D03*
X391969D03*
X388819D03*
X385670D03*
X382520D03*
X379370D03*
X376221D03*
X373071D03*
X369922D03*
X366772D03*
X363622D03*
X360473D03*
X357323D03*
X354174D03*
X351024D03*
G54D54*
G01X181458Y235984D02*
X179980Y233030D01*
G03X180203Y232359I447J-224D01*
G01X180204D01*
X180651Y232135D01*
G02X181964Y230333I-1085J-2170D01*
G01X182251Y228453D01*
G02X182171Y226340I-5559J-848D01*
G01X182100Y219617D01*
Y219600D01*
X182043Y218122D01*
X181600Y216200D01*
X180100Y214300D01*
X178468Y211552D01*
G03X178136Y210578I2150J-1276D01*
G01X177139Y202392D01*
G02X177124Y202288I-2481J305D01*
G01X177107Y202182D01*
G02X177087Y202077I-2465J415D01*
G01X176290Y198282D01*
G03X176237Y197740I2447J-513D01*
G01X176399Y183133D01*
G03X176416Y182868I2500J27D01*
G01X177263Y175666D01*
X185627Y158846D01*
X185608Y158818D01*
X185613Y158795D01*
X185661Y158551D01*
X185709Y158305D01*
X186033Y156643D01*
X185925Y155297D01*
X185900Y155200D01*
X185500Y153600D01*
X182700Y150200D01*
X182200Y148500D01*
X182054Y138909D01*
X181791Y136908D01*
X179641Y134052D01*
X179344Y133656D01*
X179342Y133653D01*
X179338Y133649D01*
X179342Y133646D01*
X179338Y133642D01*
X178384Y131972D01*
X178063Y129405D01*
Y118034D01*
X178098Y117908D01*
X178100Y117900D01*
X188800Y78800D01*
X178400Y13900D01*
X133100Y-51600D01*
X132726Y-55822D01*
Y-57237D01*
G03X133214Y-58413I1664J1D01*
G01X133215Y-58414D01*
G02X133701Y-59589I-1177J-1175D01*
G01Y-65409D01*
G01X130551D02*
Y-59638D01*
G02X131038Y-58461I1666J0D01*
G01X131184Y-58315D01*
G03X131526Y-57491I-822J824D01*
G01Y-55768D01*
X131904Y-51495D01*
X131932Y-51178D01*
X132785Y-49944D01*
X132610Y-48984D01*
X133463Y-47751D01*
X134423Y-47576D01*
X135277Y-46342D01*
X135102Y-45382D01*
X135955Y-44148D01*
X136915Y-43973D01*
X137768Y-42740D01*
X139406Y-40371D01*
X177258Y14359D01*
X187573Y78734D01*
X176942Y117584D01*
X176941Y117588D01*
X176900Y117737D01*
X176863Y117870D01*
Y129480D01*
X176872Y129552D01*
X177223Y132359D01*
X178371Y134370D01*
X178375Y134374D01*
X178379Y134371D01*
X178383Y134375D01*
X178530Y134572D01*
X178681Y134773D01*
X180642Y137377D01*
X180855Y138997D01*
X181002Y148682D01*
X181617Y150774D01*
X184401Y154154D01*
X184736Y155492D01*
X184823Y156575D01*
X184531Y158075D01*
X184435Y158566D01*
X184430Y158589D01*
X184405Y158605D01*
X184404Y158608D01*
X176134Y175240D01*
G02X176085Y175404I447J223D01*
G01X175224Y182728D01*
G02X175199Y183120I3675J431D01*
G01X175037Y197726D01*
G02X175115Y198529I3700J46D01*
G01X175912Y202325D01*
X175913Y202327D01*
G03X175922Y202378I-1274J251D01*
G01X175939Y202481D01*
X175940Y202484D01*
G03X175947Y202538I-1284J194D01*
G01X176944Y210723D01*
G02X177436Y212165I3673J-448D01*
G01X179091Y214953D01*
G02X179129Y215008I429J-256D01*
G01X179944Y216040D01*
X180491Y216732D01*
X180848Y218281D01*
X180900Y219646D01*
X180972Y226491D01*
G03X181064Y228272I-4281J1114D01*
G01X180777Y230151D01*
G03X180114Y231061I-1211J-186D01*
G01X179668Y231285D01*
X179667D01*
G03X178996Y231062I-224J-447D01*
G01X177518Y228109D01*
G01X171496Y-65409D02*
Y-58949D01*
G03X171155Y-58126I-1164J0D01*
G01X171009Y-57980D01*
G02X170522Y-56804I1176J1176D01*
G01Y-55604D01*
X169700Y-53500D01*
X169900Y-50700D01*
X188800Y-700D01*
X206300Y88400D01*
X206312Y88463D01*
X209430Y124336D01*
X209800Y128685D01*
X209519Y130283D01*
X209496Y130784D01*
X209495Y130785D01*
X209498D01*
X209497Y130786D01*
G02X209486Y130870I3410J489D01*
G02X211111Y134208I3421J399D01*
G03X213387Y137622I-2544J4162D01*
G03X213767Y145631I-37231J5780D01*
G02X213893Y148919I16795J1003D01*
G03X212143Y152234I-3190J436D01*
G01X211702Y152454D01*
X211697Y152456D01*
X211696D01*
G02X211472Y153127I224J448D01*
G01X212497Y155172D01*
X212953Y155984D01*
G01X193268Y148109D02*
X192453Y149839D01*
X191793Y151161D01*
G03X191122Y151385I-447J-223D01*
G01X191121D01*
X190673Y151161D01*
G03X189854Y150182I715J-1430D01*
G03X189911Y147174I4817J-1413D01*
G02X190194Y142860I-8047J-2694D01*
G03X189967Y139056I14168J-2754D01*
G03X191159Y135027I9817J713D01*
G03X192725Y133379I3913J2150D01*
G02X193940Y130594I-2580J-2783D01*
G01X193936Y130590D01*
X193939D01*
X193938Y130589D01*
X193937Y128885D01*
X193000Y126900D01*
X190000Y119700D01*
X189600Y111800D01*
X195600Y78800D01*
X181800Y1600D01*
X164581Y-43669D01*
X164980Y-44559D01*
X164447Y-45961D01*
X163557Y-46360D01*
X163023Y-47762D01*
X163423Y-48653D01*
X162890Y-50055D01*
X162000Y-50454D01*
X161073Y-52890D01*
Y-57284D01*
G03X161560Y-58460I1663J0D01*
G02X162048Y-59638I-1178J-1178D01*
G01Y-65409D01*
G01X209018Y148109D02*
X209643Y149463D01*
X210487Y151159D01*
G02X211158Y151383I447J-223D01*
G01X211159D01*
X211607Y151160D01*
G02X212704Y149082I-904J-1806D01*
G03X212569Y145560I17858J-2448D01*
G02X212201Y137806I-36413J-2158D01*
G02X210485Y135232I-3634J564D01*
G03X208294Y130731I2422J-3963D01*
G01X208295Y130730D01*
X208296D01*
X208297Y130729D01*
X208323Y130151D01*
X208591Y128631D01*
X208234Y124439D01*
X205122Y88631D01*
X187641Y-370D01*
X172371Y-40768D01*
X171481Y-41169D01*
X170951Y-42572D01*
X171352Y-43462D01*
X170822Y-44865D01*
X169933Y-45266D01*
X169402Y-46669D01*
X169804Y-47559D01*
X168715Y-50439D01*
X168483Y-53685D01*
X169321Y-55830D01*
X169322D01*
Y-56806D01*
G02X168980Y-57630I-1164J0D01*
G01X168834Y-57776D01*
G03X168347Y-58953I1179J-1177D01*
G01Y-65409D01*
G01X158898D02*
Y-59191D01*
G02X159386Y-58014I1663J0D01*
G01X159450Y-57950D01*
G03X159873Y-56928I-1023J1022D01*
G01Y-52669D01*
X159914Y-52561D01*
X162304Y-46278D01*
X164884Y-39492D01*
X180641Y1939D01*
X194380Y78798D01*
X188394Y111722D01*
X188812Y119969D01*
X191902Y127388D01*
X192737Y129154D01*
Y130094D01*
X192738Y130593D01*
X192740Y130595D01*
G03X191980Y132430I-2595J0D01*
G02X190107Y134449I3092J4747D01*
G02X188770Y138969I9677J5320D01*
G02X189016Y143089I15592J1136D01*
G03X188773Y146793I-7152J1391D01*
G02X188702Y150520I5898J1977D01*
G02X190136Y152235I2686J-789D01*
G01X190583Y152458D01*
X190584D01*
G03X190808Y153129I-224J448D01*
G01X189333Y155984D01*
G01X283818D02*
X282337Y153127D01*
G03X282561Y152456I448J-223D01*
G01X282562D01*
X282567Y152454D01*
X283008Y152234D01*
G02X284758Y148919I-1440J-2879D01*
G03X284632Y145631I16669J-2285D01*
G02X284252Y137622I-37611J-2229D01*
G02X283396Y135557I-2921J1D01*
G01X281690Y133850D01*
G03X280590Y131194I2656J-2656D01*
G01Y129994D01*
X280000Y126500D01*
X227000Y-51600D01*
X226800Y-55000D01*
X227144Y-56127D01*
X227215Y-57326D01*
G03X227702Y-58502I1663J0D01*
G02X228189Y-59678I-1176J-1176D01*
G01Y-65409D01*
G01X218740D02*
Y-59600D01*
G03X218253Y-58424I-1663J0D01*
G02X217766Y-57248I1176J1176D01*
G01X217767Y-57247D01*
X217764D01*
X217765Y-57246D01*
X218009Y-54004D01*
X217800Y-51300D01*
X263568Y124785D01*
X264841Y130623D01*
Y131279D01*
G02X265940Y133850I3755J-85D01*
G01X267646Y135557D01*
G03X268502Y137622I-2065J2066D01*
G03X268882Y145631I-37231J5780D01*
G02X269008Y148919I16795J1003D01*
G03X267258Y152234I-3190J436D01*
G01X266817Y152454D01*
X266812Y152456D01*
X266811D01*
G02X266587Y153127I224J448D01*
G01X267648Y155236D01*
X268073Y155984D01*
G01X209292Y-65409D02*
Y-59653D01*
G03X208804Y-58475I-1666J0D01*
G02X208317Y-57299I1176J1176D01*
G01X208318Y-57298D01*
X208315D01*
X208316Y-57297D01*
X208407Y-56099D01*
X207900Y-54900D01*
X207580Y-50021D01*
X240999Y128283D01*
X241020Y130607D01*
X241004Y130709D01*
G02X242606Y134208I3399J560D01*
G03X244882Y137622I-2544J4162D01*
G03X245262Y145631I-37231J5780D01*
G02X245388Y148919I16795J1003D01*
G03X243638Y152234I-3190J436D01*
G01X243197Y152454D01*
X243192Y152456D01*
X243191D01*
G02X242967Y153127I224J448D01*
G01X244448Y155984D01*
G01X199843Y-65409D02*
Y-59303D01*
G03X199356Y-58127I-1663J0D01*
G02X198868Y-56950I1175J1177D01*
G01Y-55750D01*
X198400Y-50000D01*
X225273Y127845D01*
X225274Y127850D01*
X225253Y130705D01*
X225242Y130785D01*
G02X226856Y134208I3410J484D01*
G03X229132Y137622I-2544J4162D01*
G03X229512Y145631I-37231J5780D01*
G02X229638Y148919I16795J1003D01*
G03X227888Y152234I-3190J436D01*
G01X227447Y152454D01*
X227442Y152456D01*
X227441D01*
G02X227217Y153127I224J448D01*
G01X228024Y154732D01*
X228703Y155984D01*
G01X247087Y-65409D02*
Y-59376D01*
G03X246600Y-58200I-1663J0D01*
G02X246112Y-57023I1175J1177D01*
G01Y-53500D01*
X284654Y74534D01*
X285179Y75835D01*
X285270Y76061D01*
X285272Y76063D01*
X285273D01*
X285275Y76065D01*
X311465Y127041D01*
X311491Y127253D01*
X311897Y130538D01*
X311869Y130708D01*
G02X313471Y134208I3398J561D01*
G03X315747Y137622I-2544J4162D01*
G03X316127Y145631I-37231J5780D01*
G02X316253Y148919I16795J1003D01*
G03X314503Y152234I-3190J436D01*
G01X314062Y152454D01*
X314057Y152456D01*
X314056D01*
G02X313832Y153127I224J448D01*
G01X314560Y154579D01*
X315313Y155984D01*
G01X299568D02*
X299220Y155390D01*
X298082Y153127D01*
G03X298306Y152456I448J-223D01*
G01X298307D01*
X298312Y152454D01*
X298753Y152234D01*
G02X300503Y148919I-1440J-2879D01*
G03X300377Y145631I16669J-2285D01*
G02X299997Y137622I-37611J-2229D01*
G02X297721Y134208I-4820J748D01*
G03X296119Y130709I1797J-2939D01*
G01X296137Y130599D01*
X296134Y130596D01*
Y130593D01*
X296178Y129971D01*
X296255Y128897D01*
X288811Y101931D01*
X288800Y101900D01*
X237000Y-51900D01*
X236664Y-56330D01*
Y-57175D01*
G03X237151Y-58351I1663J0D01*
G02X237638Y-59527I-1176J-1176D01*
G01Y-65409D01*
G01X279883Y148109D02*
X280113Y148670D01*
X281352Y151159D01*
G02X282023Y151383I447J-223D01*
G01X282024D01*
X282472Y151160D01*
G02X283569Y149082I-904J-1806D01*
G03X283434Y145560I17858J-2448D01*
G02X283049Y137704I-36412J-2153D01*
G02X283051Y137622I-1718J-83D01*
G02X282547Y136406I-1720J0D01*
G01X280840Y134699D01*
G03X279390Y131194I3507J-3503D01*
G01Y130095D01*
X278828Y126772D01*
X228552Y-42177D01*
X227694Y-42642D01*
X227266Y-44080D01*
X227730Y-44938D01*
X227303Y-46375D01*
X226444Y-46840D01*
X226017Y-48278D01*
X226481Y-49136D01*
X225810Y-51391D01*
X225702Y-53229D01*
X225589Y-55144D01*
X225996Y-56477D01*
X226015Y-57397D01*
G02X225529Y-58572I-1663J0D01*
G01X225528Y-58573D01*
G03X225040Y-59749I1176J-1177D01*
G01Y-65409D01*
G01X264133Y148109D02*
X264363Y148670D01*
X265602Y151159D01*
G02X266273Y151383I447J-223D01*
G01X266274D01*
X266722Y151160D01*
G02X267819Y149082I-904J-1806D01*
G03X267684Y145560I17858J-2448D01*
G02X267299Y137704I-36412J-2153D01*
G02X267301Y137622I-1718J-83D01*
G02X266797Y136406I-1720J0D01*
G01X265090Y134699D01*
G03X263641Y131292I3507J-3503D01*
G01Y130753D01*
X262400Y125064D01*
X218791Y-42715D01*
X217949Y-43209D01*
X217572Y-44661D01*
X218066Y-45502D01*
X217689Y-46954D01*
X216847Y-47448D01*
X216470Y-48900D01*
X216964Y-49741D01*
X216587Y-51193D01*
X216805Y-54005D01*
X216684Y-55600D01*
Y-55610D01*
X216685D01*
X216568Y-57154D01*
X216566Y-57156D01*
G02X216079Y-58332I-1663J0D01*
G03X215591Y-59509I1175J-1177D01*
G01Y-65409D01*
G01X240513Y148109D02*
X241982Y151159D01*
G02X242653Y151383I447J-223D01*
G01X242654D01*
X243102Y151160D01*
G02X244199Y149082I-904J-1806D01*
G03X244064Y145560I17858J-2448D01*
G02X243696Y137806I-36413J-2158D01*
G02X241980Y135232I-3634J564D01*
G01X241979Y135231D01*
G03X239819Y130514I2423J-3963D01*
G01X239800Y128400D01*
X208039Y-41057D01*
X207233Y-41609D01*
X206957Y-43083D01*
X207508Y-43888D01*
X207232Y-45363D01*
X206426Y-45914D01*
X206150Y-47388D01*
X206701Y-48193D01*
X206400Y-49800D01*
X206372Y-49949D01*
X206715Y-55181D01*
X207188Y-56298D01*
X207119Y-57207D01*
X207117Y-57206D01*
G02X206631Y-58381I-1663J0D01*
G01X206630Y-58382D01*
G03X206142Y-59558I1176J-1177D01*
G01Y-65409D01*
G01X196693D02*
Y-59307D01*
G02X197181Y-58131I1664J-1D01*
G01X197182Y-58130D01*
G03X197668Y-56955I-1177J1175D01*
G01Y-55799D01*
X197192Y-49958D01*
X197213Y-49821D01*
X197529Y-47732D01*
X196949Y-46947D01*
X197174Y-45464D01*
X197959Y-44885D01*
X198183Y-43402D01*
X197604Y-42616D01*
X197828Y-41133D01*
X198613Y-40554D01*
X224073Y127936D01*
X224053Y130616D01*
G02X226230Y135232I4599J652D01*
G03X227946Y137806I-1918J3138D01*
G03X228314Y145560I-36045J5596D01*
G02X228449Y149082I17993J1074D01*
G03X227352Y151160I-2001J272D01*
G01X226904Y151383D01*
X226903D01*
G03X226232Y151159I-224J-447D01*
G01X225406Y149499D01*
X224763Y148109D01*
G01X311378D02*
X311958Y149372D01*
X312847Y151159D01*
G02X313518Y151383I447J-223D01*
G01X313519D01*
X313967Y151160D01*
G02X315064Y149082I-904J-1806D01*
G03X314929Y145560I17858J-2448D01*
G02X314561Y137806I-36413J-2158D01*
G02X312845Y135232I-3634J564D01*
G03X310684Y130513I2422J-3963D01*
G01X310300Y127400D01*
X284157Y76517D01*
X284155Y76515D01*
X284159Y76513D01*
X284157Y76511D01*
X284127Y76438D01*
X284066Y76284D01*
X283520Y74933D01*
X247954Y-43218D01*
X247094Y-43680D01*
X246662Y-45116D01*
X247124Y-45976D01*
X246691Y-47412D01*
X245832Y-47874D01*
X245399Y-49310D01*
X245861Y-50170D01*
X244912Y-53323D01*
Y-57400D01*
G02X244426Y-58575I-1663J0D01*
G01X244425Y-58576D01*
G03X243937Y-59752I1176J-1177D01*
G01Y-65409D01*
G01X295628Y148109D02*
X295943Y148839D01*
X297097Y151159D01*
G02X297768Y151383I447J-223D01*
G01X297769D01*
X297777Y151379D01*
X298217Y151160D01*
G02X299314Y149082I-904J-1806D01*
G03X299179Y145560I17858J-2448D01*
G02X298811Y137806I-36413J-2158D01*
G02X297095Y135232I-3634J564D01*
G03X294934Y130514I2422J-3963D01*
G01Y130513D01*
X294936Y130511D01*
Y130508D01*
X294972Y130008D01*
X295043Y129017D01*
X287665Y102292D01*
X238610Y-43357D01*
X237736Y-43791D01*
X237257Y-45212D01*
X237691Y-46087D01*
X237212Y-47508D01*
X236338Y-47942D01*
X235859Y-49363D01*
X236293Y-50237D01*
X235814Y-51659D01*
X235803Y-51810D01*
X235464Y-56284D01*
Y-57146D01*
G02X234976Y-58324I-1666J0D01*
G03X234489Y-59500I1176J-1176D01*
G01Y-65409D01*
G01X350748Y148109D02*
X350247Y149211D01*
X349273Y151161D01*
G03X348602Y151385I-447J-223D01*
G01X348601D01*
X348153Y151161D01*
G03X347422Y149396I1765J-1765D01*
G01Y147573D01*
G02X342519Y142670I-4903J0D01*
G03X341443Y142225I-1J-1521D01*
G01X339881Y140662D01*
G03X339488Y139713I949J-949D01*
G01Y137640D01*
G02X338424Y135071I-3633J0D01*
G01X336593Y133240D01*
G03X335550Y130722I2518J-2518D01*
G01Y130504D01*
G02X335540Y130150I-6365J3D01*
G01X335445Y128451D01*
X334953Y125662D01*
X333478Y123554D01*
X328486Y120060D01*
X295165Y72472D01*
X267427Y-42653D01*
X267936Y-43485D01*
X267585Y-44943D01*
X266752Y-45453D01*
X266401Y-46911D01*
X266910Y-47743D01*
X266559Y-49202D01*
X265726Y-49711D01*
X265375Y-51169D01*
X265331Y-51355D01*
X265010Y-53178D01*
Y-57192D01*
G03X265498Y-58369I1663J0D01*
G02X265985Y-59545I-1176J-1176D01*
G01Y-65409D01*
G01X334998Y148109D02*
X334497Y149211D01*
X333523Y151161D01*
G03X332852Y151385I-447J-223D01*
G01X332851D01*
X332403Y151161D01*
G03X331672Y149396I1765J-1765D01*
G01Y147573D01*
G02X326769Y142670I-4903J0D01*
G03X325693Y142225I-1J-1521D01*
G01X324131Y140662D01*
G03X323738Y139713I949J-949D01*
G01Y137640D01*
G02X322674Y135071I-3633J0D01*
G01X320843Y133240D01*
G03X319800Y130722I2518J-2518D01*
G01Y128998D01*
X316879Y112426D01*
X313500Y107600D01*
X290479Y74723D01*
X259410Y-38950D01*
X259893Y-39797D01*
X259498Y-41244D01*
X258650Y-41728D01*
X258255Y-43175D01*
X258738Y-44022D01*
X258343Y-45469D01*
X257495Y-45953D01*
X257100Y-47400D01*
X255561Y-55451D01*
Y-57172D01*
G03X256048Y-58348I1663J0D01*
G02X256536Y-59526I-1178J-1178D01*
G01Y-65409D01*
G01X346813Y155984D02*
X347297Y155113D01*
X348288Y153129D01*
G02X348064Y152458I-448J-223D01*
G01X348063D01*
X347459Y152157D01*
G03X346222Y149395I2460J-2760D01*
G01Y147573D01*
G02X342519Y143870I-3703J0D01*
G03X340594Y143074I-2J-2722D01*
G01X339031Y141511D01*
G03X338288Y139712I1800J-1796D01*
G01Y137639D01*
X338287Y137640D01*
G02X337575Y135920I-2432J0D01*
G01X335744Y134089D01*
G03X334350Y130723I3367J-3366D01*
G01Y130505D01*
G02X334341Y130217I-5165J17D01*
G01X334250Y128590D01*
X333817Y126132D01*
X332616Y124416D01*
X327624Y120922D01*
X309583Y95156D01*
X294051Y72974D01*
X264544Y-49490D01*
X264195Y-50885D01*
X263810Y-53073D01*
Y-57111D01*
G02X263322Y-58289I-1666J0D01*
G03X262835Y-59465I1176J-1176D01*
G01Y-65409D01*
G01X331063Y155984D02*
X331547Y155113D01*
X332538Y153129D01*
G02X332314Y152458I-448J-223D01*
G01X332313D01*
X331709Y152157D01*
G03X330472Y149395I2460J-2760D01*
G01Y147573D01*
G02X326769Y143870I-3703J0D01*
G03X324844Y143074I-2J-2722D01*
G01X323281Y141511D01*
G03X322538Y139712I1800J-1796D01*
G01Y137639D01*
X322537Y137640D01*
G02X321825Y135920I-2432J0D01*
G01X319994Y134089D01*
G03X318600Y130723I3367J-3366D01*
G01Y129103D01*
X315743Y112896D01*
X312517Y108289D01*
X289496Y75411D01*
X289495D01*
X289376Y75241D01*
X255942Y-47084D01*
X255930Y-47129D01*
X254361Y-55337D01*
Y-57151D01*
G02X253875Y-58326I-1663J0D01*
G01X253874Y-58327D01*
G03X253386Y-59503I1176J-1177D01*
G01Y-65409D01*
G01X445238Y148109D02*
X444749Y149185D01*
X443763Y151161D01*
G03X443171Y151416I-447J-223D01*
G03X443092Y151385I142J-479D01*
G01X443091D01*
X442643Y151161D01*
G03X441912Y149396I1765J-1765D01*
G01Y147573D01*
G02X437009Y142670I-4903J0D01*
G03X435933Y142225I-1J-1521D01*
G01X434371Y140662D01*
G03X433978Y139713I949J-949D01*
G01Y137640D01*
G02X432914Y135071I-3633J0D01*
G01X431083Y133240D01*
G03X430040Y130722I2518J-2518D01*
G01Y128851D01*
X429699Y126913D01*
X428529Y125241D01*
X428528Y125240D01*
X428514D01*
X427084Y123810D01*
X420500Y119200D01*
X403356Y107196D01*
X353568Y98418D01*
X347249Y93993D01*
X346889Y93633D01*
Y93621D01*
X346887Y93619D01*
X322692Y59066D01*
X309757Y-14315D01*
X313555Y-35852D01*
X314354Y-36412D01*
X314615Y-37889D01*
X314055Y-38688D01*
X314315Y-40166D01*
X315115Y-40725D01*
X315375Y-42202D01*
X314816Y-43002D01*
X315076Y-44479D01*
X321379Y-53481D01*
X321703Y-55319D01*
Y-57092D01*
G03X322044Y-57915I1164J0D01*
G01X322190Y-58061D01*
G02X322677Y-59237I-1176J-1176D01*
G01Y-65409D01*
G01X429488Y148109D02*
X429031Y149123D01*
X428013Y151161D01*
G03X427342Y151385I-447J-223D01*
G01X427341D01*
X426893Y151161D01*
G03X426162Y149396I1765J-1765D01*
G01Y147573D01*
G02X421259Y142670I-4903J0D01*
G03X420183Y142225I-1J-1521D01*
G01X418621Y140662D01*
G03X418228Y139713I949J-949D01*
G01Y137640D01*
G02X417164Y135071I-3633J0D01*
G01X415333Y133240D01*
G03X414340Y130250I2485J-2485D01*
G01X414361Y130104D01*
X414064Y127182D01*
X414041Y127171D01*
X414034Y127154D01*
X413460Y125551D01*
X410165Y120846D01*
X407100Y118700D01*
X398507Y112683D01*
X352100Y104500D01*
X344990Y99522D01*
X318142Y61179D01*
X304600Y-15600D01*
X304485Y-16257D01*
X304326Y-17358D01*
X303819Y-21228D01*
X310046Y-46920D01*
X310880Y-47428D01*
X311233Y-48885D01*
X310725Y-49718D01*
X311078Y-51176D01*
X311911Y-51684D01*
X312265Y-53142D01*
X311757Y-53975D01*
X312110Y-55433D01*
X312251Y-57129D01*
Y-57132D01*
X312254Y-57135D01*
G03X312742Y-58313I1666J0D01*
G02X313229Y-59489I-1176J-1176D01*
G01Y-65409D01*
G01X413738Y148109D02*
X413047Y149591D01*
X412263Y151161D01*
G03X411592Y151385I-447J-223D01*
G01X411591D01*
X411143Y151161D01*
G03X410412Y149396I1765J-1765D01*
G01Y147573D01*
G02X405509Y142670I-4903J0D01*
G03X404433Y142225I-1J-1521D01*
G01X402871Y140662D01*
G03X402478Y139713I949J-949D01*
G01Y137640D01*
G02X401414Y135071I-3633J0D01*
G01X399583Y133240D01*
G03X398540Y130722I2518J-2518D01*
G01Y128915D01*
X398248Y127257D01*
X395595Y123462D01*
X383356Y114894D01*
X378882Y114105D01*
X377572Y113874D01*
X350330Y109072D01*
X341062Y102582D01*
X313839Y63704D01*
X298577Y-22838D01*
X301563Y-46822D01*
X302333Y-47422D01*
X302519Y-48910D01*
X301919Y-49680D01*
X302104Y-51169D01*
X302874Y-51768D01*
X303060Y-53257D01*
X302460Y-54027D01*
X302717Y-56089D01*
X302718Y-56090D01*
X302719D01*
X302720Y-56091D01*
X302805Y-57087D01*
G03X303292Y-58263I1663J0D01*
G02X303780Y-59441I-1178J-1178D01*
G01Y-65409D01*
G01X397993Y148109D02*
X397734Y148725D01*
X396518Y151161D01*
G03X395847Y151385I-447J-223D01*
G01X395846D01*
X395398Y151161D01*
G03X394667Y149396I1765J-1765D01*
G01Y147573D01*
G02X389764Y142670I-4903J0D01*
G03X388688Y142225I-1J-1521D01*
G01X387126Y140662D01*
G03X386733Y139713I949J-949D01*
G01Y137640D01*
G02X385669Y135071I-3633J0D01*
G01X383838Y133240D01*
G03X382796Y130723I2519J-2517D01*
G01X382795Y130618D01*
X382211Y127303D01*
X381379Y126114D01*
X381378Y126113D01*
X381364D01*
X380161Y124910D01*
X369644Y117546D01*
X351800Y114400D01*
X347082Y113568D01*
X338412Y107497D01*
X309187Y65758D01*
X290828Y-38356D01*
X291975Y-46926D01*
X292751Y-47518D01*
X292950Y-49005D01*
X292358Y-49780D01*
X292557Y-51267D01*
X293332Y-51860D01*
X293531Y-53346D01*
X292939Y-54122D01*
X293339Y-57112D01*
G02X293347Y-57179I-2330J-312D01*
G01X293346D01*
X293353Y-57235D01*
X293356Y-57238D01*
G03X293844Y-58415I1663J0D01*
G02X294331Y-59591I-1176J-1176D01*
G01Y-65409D01*
G01X382243Y148109D02*
X382064Y148566D01*
X380768Y151161D01*
G03X380097Y151385I-447J-223D01*
G01X380096D01*
X379648Y151161D01*
G03X378917Y149396I1765J-1765D01*
G01Y147573D01*
G02X374014Y142670I-4903J0D01*
G03X372938Y142225I-1J-1521D01*
G01X371376Y140662D01*
G03X370983Y139713I949J-949D01*
G01Y137640D01*
G02X369919Y135071I-3633J0D01*
G01X368088Y133240D01*
G03X367045Y130722I2518J-2518D01*
G02X366987Y129239I-19044J2D01*
G01Y129238D01*
G02X366848Y127992I-18987J1487D01*
G01X365228Y125680D01*
X362400Y123700D01*
X358711Y121117D01*
X343854Y118499D01*
X335616Y112730D01*
X304070Y67678D01*
X284821Y-39479D01*
X285378Y-40280D01*
X285113Y-41757D01*
X284312Y-42314D01*
X284046Y-43790D01*
X284604Y-44591D01*
X284338Y-46068D01*
X283537Y-46625D01*
X283272Y-48101D01*
X283485Y-51207D01*
X283908Y-57319D01*
G03X284395Y-58495I1663J0D01*
G02X284882Y-59671I-1176J-1176D01*
G01Y-65409D01*
G01X366498Y148109D02*
X366236Y148732D01*
X365023Y151161D01*
G03X364352Y151385I-447J-223D01*
G01X364351D01*
X363903Y151161D01*
G03X363172Y149396I1765J-1765D01*
G01Y147573D01*
G02X358269Y142670I-4903J0D01*
G03X357193Y142225I-1J-1521D01*
G01X355631Y140662D01*
G03X355238Y139713I949J-949D01*
G01Y137640D01*
G02X354174Y135071I-3633J0D01*
G01X352343Y133240D01*
G03X351300Y130722I2518J-2518D01*
G01Y129023D01*
X350994Y127285D01*
X349904Y125728D01*
X348276Y124588D01*
X348275Y124587D01*
X347289Y123897D01*
X341300Y122840D01*
X332693Y116812D01*
X331564Y115683D01*
Y115684D01*
X331204Y115324D01*
Y115312D01*
X331202Y115310D01*
X299659Y70263D01*
X276903Y-40770D01*
X277440Y-41585D01*
X277139Y-43054D01*
X276325Y-43592D01*
X276023Y-45061D01*
X276561Y-45876D01*
X276260Y-47345D01*
X275445Y-47883D01*
X275144Y-49352D01*
X274459Y-53234D01*
Y-57341D01*
G03X274946Y-58517I1663J0D01*
G02X275433Y-59693I-1176J-1176D01*
G01Y-65409D01*
G01X441298Y155984D02*
X441824Y155033D01*
X442778Y153129D01*
G02X442554Y152458I-448J-223D01*
G01X442553D01*
X441949Y152157D01*
G03X440712Y149395I2460J-2760D01*
G01Y147573D01*
G02X437009Y143870I-3703J0D01*
G03X435084Y143074I-2J-2722D01*
G01X433521Y141511D01*
G03X432778Y139712I1800J-1796D01*
G01Y137639D01*
X432777Y137640D01*
G02X432065Y135920I-2432J0D01*
G01X430234Y134089D01*
G03X428840Y130723I3367J-3366D01*
G01Y128956D01*
X428563Y127383D01*
X427667Y126103D01*
X427665Y126101D01*
Y126089D01*
X426309Y124734D01*
X419811Y120183D01*
X402886Y108332D01*
X353098Y99554D01*
X346474Y94917D01*
X346040Y94482D01*
X346026D01*
X346025Y94481D01*
X321556Y59536D01*
X308538Y-14315D01*
X313940Y-44949D01*
X320243Y-53951D01*
X320503Y-55424D01*
Y-57019D01*
G02X320016Y-58195I-1663J0D01*
G01X319870Y-58341D01*
G03X319528Y-59166I824J-825D01*
G01Y-65409D01*
G01X425553Y155984D02*
X426062Y155064D01*
X427028Y153129D01*
G02X426804Y152458I-448J-223D01*
G01X426803D01*
X426199Y152157D01*
G03X424962Y149395I2460J-2760D01*
G01Y147573D01*
G02X421259Y143870I-3703J0D01*
G03X419334Y143074I-2J-2722D01*
G01X417771Y141511D01*
G03X417028Y139712I1800J-1796D01*
G01Y137639D01*
X417027Y137640D01*
G02X416315Y135920I-2432J0D01*
G01X414484Y134089D01*
G03X413152Y130078I3334J-3334D01*
G01X412900Y127600D01*
X412911Y127576D01*
X412904Y127559D01*
X412903Y127558D01*
X412904D01*
X412384Y126108D01*
X409303Y121708D01*
X406411Y119683D01*
X398037Y113819D01*
X351630Y105636D01*
X344128Y100384D01*
X317006Y61649D01*
X303418Y-15392D01*
X303299Y-16067D01*
X303219Y-16621D01*
X303137Y-17194D01*
X302629Y-21073D01*
X302600Y-21294D01*
X310921Y-55625D01*
X311055Y-57228D01*
Y-57231D01*
X311052Y-57234D01*
G02X310567Y-58344I-1662J65D01*
G03X310079Y-59522I1178J-1178D01*
G01Y-65409D01*
G01X300630D02*
Y-59470D01*
G02X301118Y-58294I1664J-1D01*
G01X301119Y-58293D01*
G03X301603Y-57185I-1178J1174D01*
G01X301527Y-56241D01*
X301526D01*
X301525Y-56240D01*
X301527D01*
X301526Y-56239D01*
X297363Y-22807D01*
X312703Y64174D01*
X340200Y103444D01*
X349860Y110208D01*
X378412Y115241D01*
X382886Y116030D01*
X394732Y124324D01*
X397112Y127727D01*
X397340Y129020D01*
Y130723D01*
G02X398734Y134089I4761J0D01*
G01X400565Y135920D01*
G03X401277Y137640I-1720J1720D01*
G01X401278Y137639D01*
Y139712D01*
G02X402021Y141511I2543J3D01*
G01X403584Y143074D01*
G02X405509Y143870I1923J-1926D01*
G03X409212Y147573I0J3703D01*
G01Y149395D01*
G02X410449Y152157I3697J2D01*
G01X411053Y152458D01*
X411054D01*
G03X411278Y153129I-224J448D01*
G01X410472Y154742D01*
X409803Y155984D01*
G01X291181Y-65409D02*
Y-59917D01*
G02X291667Y-58744I1659J0D01*
G01X291816Y-58595D01*
G03X292153Y-57781I-815J814D01*
G01Y-57366D01*
G03X292148Y-57268I-1151J-10D01*
G01X289613Y-38331D01*
X308051Y66228D01*
X337550Y108359D01*
X346612Y114704D01*
X351592Y115582D01*
X369174Y118682D01*
X379386Y125834D01*
X380515Y126962D01*
Y126974D01*
X380517Y126976D01*
X381075Y127773D01*
X381595Y130723D01*
G02X382989Y134089I4761J0D01*
G01X384820Y135920D01*
G03X385532Y137640I-1720J1720D01*
G01X385533Y137639D01*
Y139712D01*
G02X386276Y141511I2543J3D01*
G01X387839Y143074D01*
G02X389764Y143870I1923J-1926D01*
G03X393467Y147573I0J3703D01*
G01Y149395D01*
G02X394704Y152157I3697J2D01*
G01X395308Y152458D01*
X395309D01*
G03X395533Y153129I-224J448D01*
G01X394292Y155606D01*
X394053Y155984D01*
G01X281733Y-65409D02*
Y-59756D01*
G02X282220Y-58580I1663J0D01*
G03X282708Y-57402I-1178J1178D01*
G01Y-57372D01*
X282707D01*
X282287Y-51290D01*
X282074Y-48183D01*
X282064Y-48035D01*
X302935Y68150D01*
X334754Y113592D01*
X343384Y119635D01*
X358241Y122253D01*
X361711Y124683D01*
X364366Y126542D01*
X365698Y128443D01*
G03X365844Y130722I-17698J2278D01*
G02X367239Y134089I4762J0D01*
G01X369070Y135920D01*
G03X369782Y137640I-1720J1720D01*
G01X369783Y137639D01*
Y139712D01*
G02X370526Y141511I2543J3D01*
G01X372089Y143074D01*
G02X374014Y143870I1923J-1926D01*
G03X377717Y147573I0J3703D01*
G01Y149395D01*
G02X378954Y152157I3697J2D01*
G01X379558Y152458D01*
X379559D01*
G03X379783Y153129I-224J448D01*
G01X378782Y155133D01*
X378308Y155984D01*
G01X362558D02*
X363035Y155131D01*
X364038Y153129D01*
G02X363814Y152458I-448J-223D01*
G01X363813D01*
X363209Y152157D01*
G03X361972Y149395I2460J-2760D01*
G01Y147573D01*
G02X358269Y143870I-3703J0D01*
G03X356344Y143074I-2J-2722D01*
G01X354781Y141511D01*
G03X354038Y139712I1800J-1796D01*
G01Y137639D01*
X354037Y137640D01*
G02X353325Y135920I-2432J0D01*
G01X351494Y134089D01*
G03X350100Y130723I3367J-3366D01*
G01Y129128D01*
X349858Y127755D01*
X349042Y126590D01*
X346819Y125033D01*
X340830Y123976D01*
X331918Y117736D01*
X330355Y116173D01*
X330341D01*
X330340Y116172D01*
X298523Y70733D01*
X274008Y-48882D01*
X273259Y-53128D01*
Y-57364D01*
G02X272773Y-58539I-1663J0D01*
G01X272772Y-58540D01*
G03X272284Y-59716I1176J-1177D01*
G01Y-65409D01*
G01X329242Y-36479D02*
G03X327842Y-38879I1357J-2400D01*
G01Y-41761D01*
X327803Y-45372D01*
X327708Y-46569D01*
G03X327831Y-47559I2492J-193D01*
G01X328721Y-49971D01*
X331152Y-56100D01*
Y-57263D01*
G03X331639Y-58439I1663J0D01*
G02X332126Y-59615I-1176J-1176D01*
G01Y-65409D01*
G01X339442Y-36479D02*
G03X338042Y-38879I1357J-2400D01*
G01Y-42166D01*
X337708Y-44078D01*
X337931Y-46284D01*
X338137Y-48272D01*
X340545Y-55970D01*
X340546Y-55973D01*
X340600Y-56146D01*
Y-57111D01*
G03X341088Y-58287I1664J1D01*
G01X341089Y-58288D01*
G02X341575Y-59463I-1177J-1175D01*
G01Y-65409D01*
G01X325242Y-36479D02*
G02X326642Y-38879I-1357J-2400D01*
G01Y-41754D01*
X326603Y-45318D01*
X326511Y-46475D01*
G03X326699Y-47960I3689J-287D01*
G01X327600Y-50400D01*
X329952Y-56330D01*
Y-57058D01*
G02X329464Y-58236I-1666J0D01*
G03X328977Y-59412I1176J-1176D01*
G01Y-65409D01*
G01X338426D02*
Y-59563D01*
G02X338913Y-58387I1663J0D01*
G03X339400Y-57211I-1176J1176D01*
G01Y-56330D01*
X339399Y-56327D01*
X336955Y-48515D01*
X336737Y-46406D01*
X336497Y-44034D01*
X336842Y-42061D01*
Y-38879D01*
G03X335442Y-36479I-2757J0D01*
G01X345642D02*
G02X347042Y-38879I-1357J-2400D01*
G01Y-43429D01*
X346849Y-47567D01*
X346894Y-47902D01*
X348388Y-54448D01*
X348849Y-56466D01*
X348840Y-56428D01*
X348849Y-57361D01*
G02X348361Y-58539I-1666J0D01*
G03X347874Y-59715I1176J-1176D01*
G01Y-65409D01*
G01X334998Y228109D02*
X333523Y231063D01*
G03X332852Y231287I-447J-223D01*
G01X332851D01*
X331883Y230803D01*
G03X331613Y230151I652J-652D01*
G01Y224725D01*
G03X332017Y217438I65920J0D01*
G03X333479Y215107I3144J348D01*
G02X335293Y211956I-2068J-3288D01*
G01X335366Y209869D01*
X335753Y207674D01*
X336095Y207186D01*
X380809Y175877D01*
X455699Y162672D01*
X461565Y158563D01*
X464206Y154792D01*
X465355Y153152D01*
X480132Y66785D01*
X455186Y-40368D01*
X455702Y-41197D01*
X455362Y-42658D01*
X454533Y-43173D01*
X454193Y-44634D01*
X454709Y-45463D01*
X454369Y-46923D01*
X453540Y-47439D01*
X453200Y-48900D01*
X452543Y-52624D01*
X453179Y-56231D01*
Y-57890D01*
G03X453666Y-59066I1663J0D01*
G02X454154Y-60244I-1178J-1178D01*
G01Y-65809D01*
G01X331063Y235984D02*
X332538Y233031D01*
G02X332314Y232360I-448J-223D01*
G01X332312D01*
X331208Y231808D01*
G03X330413Y230150I1327J-1656D01*
G01Y224725D01*
G03X330824Y217306I67120J-3D01*
G03X332840Y214091I4337J480D01*
G02X334093Y211914I-1430J-2272D01*
G01X334169Y209743D01*
X334617Y207203D01*
X335233Y206324D01*
X380338Y174741D01*
X455229Y161536D01*
X460703Y157701D01*
X461531Y156519D01*
X464215Y152687D01*
X464217Y152684D01*
X478908Y66822D01*
X452024Y-48655D01*
X451324Y-52624D01*
X451979Y-56336D01*
Y-57931D01*
G02X451491Y-59109I-1666J0D01*
G03X451004Y-60285I1176J-1176D01*
G01Y-65809D01*
G01X460453D02*
Y-60136D01*
G02X460940Y-58960I1663J0D01*
G01X460954Y-58946D01*
G03X461428Y-57801I-1146J1145D01*
G01Y-49705D01*
X461818Y-47492D01*
X461820Y-47477D01*
X484315Y63990D01*
X484333Y64261D01*
X484340Y64504D01*
X468918Y154709D01*
X464011Y161717D01*
X457080Y166571D01*
X389568Y178476D01*
X352767Y204244D01*
X350257Y207829D01*
X349919Y209743D01*
X349843Y211914D01*
G03X348590Y214091I-2683J-95D01*
G02X346574Y217306I2321J3695D01*
G02X346163Y224725I66709J7416D01*
G01Y230150D01*
G02X346958Y231808I2122J2D01*
G01X348062Y232360D01*
X348064D01*
G03X348288Y233031I-224J448D01*
G01X346813Y235984D01*
G01X349642Y-36479D02*
G03X348242Y-38879I1357J-2400D01*
G01Y-43457D01*
X348053Y-47515D01*
X348077Y-47688D01*
X349558Y-54181D01*
X350039Y-56286D01*
X350049Y-56330D01*
Y-57460D01*
G03X350536Y-58636I1663J0D01*
G02X351024Y-59814I-1178J-1178D01*
G01Y-65409D01*
G01X359842Y-36479D02*
G03X358442Y-38879I1357J-2400D01*
G01Y-43454D01*
X358329Y-46256D01*
X358330D01*
X358329Y-46257D01*
X358303Y-46757D01*
X358493Y-50450D01*
X359498Y-56226D01*
Y-57136D01*
G03X359985Y-58312I1663J0D01*
G02X360473Y-59490I-1178J-1178D01*
G01Y-65409D01*
G01X369922D02*
Y-59383D01*
G03X369434Y-58205I-1666J0D01*
G02X368947Y-57029I1176J1176D01*
G01Y-55604D01*
X368477Y-47897D01*
X368480Y-47847D01*
X368547Y-47400D01*
X368555Y-47224D01*
X368557Y-44852D01*
X368669Y-43248D01*
X368671Y-43299D01*
Y-38480D01*
G02X370042Y-36479I2728J-399D01*
G01X379370Y-65409D02*
Y-59130D01*
G03X378883Y-57954I-1663J0D01*
G02X378396Y-56778I1176J1176D01*
G01Y-54841D01*
X378624Y-49601D01*
X378825Y-47959D01*
X378827Y-47946D01*
X378841Y-47934D01*
X378658Y-45755D01*
X378524Y-44183D01*
X378842Y-41975D01*
Y-38879D01*
G02X380242Y-36479I2757J0D01*
G01X390442D02*
G03X389042Y-38879I1357J-2400D01*
G01Y-41945D01*
X389035Y-42079D01*
X388864Y-45771D01*
X388968Y-47417D01*
X388964Y-47421D01*
Y-47425D01*
X388873Y-49124D01*
X388300Y-51000D01*
X387844Y-56330D01*
Y-57055D01*
G03X388332Y-58232I1663J0D01*
G02X388819Y-59408I-1176J-1176D01*
G01Y-65409D01*
G01X398268D02*
Y-59329D01*
G03X397780Y-58151I-1666J0D01*
G02X397293Y-56975I1176J1176D01*
G01Y-51258D01*
X399090Y-47630D01*
X399159Y-47491D01*
X399221Y-47460D01*
X399223Y-47456D01*
X399242Y-45346D01*
Y-38879D01*
G02X400642Y-36479I2757J0D01*
G01X357323Y-65409D02*
Y-59466D01*
G02X357810Y-58290I1663J0D01*
G03X358298Y-57112I-1178J1178D01*
G01Y-56330D01*
X357300Y-50600D01*
X357297Y-50578D01*
X357101Y-46756D01*
X357130Y-46201D01*
X357242Y-43429D01*
Y-38879D01*
G03X355842Y-36479I-2757J0D01*
G01X366772Y-65409D02*
Y-59228D01*
G02X367259Y-58052I1663J0D01*
G03X367747Y-56874I-1178J1178D01*
G01Y-55641D01*
X367274Y-47892D01*
X367286Y-47717D01*
X367360Y-47223D01*
Y-47217D01*
X367355Y-47216D01*
Y-47210D01*
X367357Y-44810D01*
X367471Y-43165D01*
Y-38908D01*
X367442Y-38879D01*
G03X366042Y-36479I-2757J0D01*
G01X376221Y-65409D02*
Y-59379D01*
G02X376708Y-58203I1663J0D01*
G03X377196Y-57025I-1178J1178D01*
G01Y-54814D01*
X377427Y-49502D01*
X377629Y-47848D01*
X377623Y-47785D01*
X377624D01*
X377462Y-45856D01*
X377316Y-44148D01*
X377642Y-41889D01*
Y-38879D01*
G03X376242Y-36479I-2757J0D01*
G01X386442D02*
G02X387842Y-38879I-1357J-2400D01*
G01Y-41945D01*
X387836Y-42020D01*
X387662Y-45781D01*
X387761Y-47353D01*
X387765Y-47357D01*
Y-47361D01*
X387682Y-48913D01*
X387152Y-50650D01*
X387115Y-50771D01*
X386644Y-56278D01*
Y-57167D01*
G02X386157Y-58343I-1663J0D01*
G03X385670Y-59519I1176J-1176D01*
G01Y-65409D01*
G01X395118D02*
Y-59182D01*
G02X395605Y-58006I1663J0D01*
G03X396093Y-56828I-1178J1178D01*
G01Y-50977D01*
X398014Y-47098D01*
X398026Y-47092D01*
X398042Y-45340D01*
Y-38879D01*
G03X396642Y-36479I-2757J0D01*
G01X473051Y-65809D02*
Y-60040D01*
G03X472564Y-58864I-1663J0D01*
G02X472077Y-57688I1176J1176D01*
G01Y-49672D01*
X472336Y-48097D01*
X473129Y-47528D01*
X473372Y-46048D01*
X472803Y-45255D01*
X473046Y-43775D01*
X473839Y-43206D01*
X474082Y-41726D01*
X473513Y-40933D01*
X473756Y-39453D01*
X474224Y-36611D01*
X490785Y64154D01*
X490786Y64166D01*
X490781Y64764D01*
Y64776D01*
X490790Y64785D01*
X490432Y66811D01*
X474971Y154499D01*
X474331Y158131D01*
X467000Y168600D01*
X459598Y173783D01*
X399513Y184376D01*
X368309Y206226D01*
X367239Y207754D01*
X366866Y209869D01*
X366793Y211956D01*
G03X364979Y215107I-3882J-137D01*
G02X363517Y217438I1682J2679D01*
G02X363113Y224725I65516J7287D01*
G01Y230151D01*
G02X363383Y230803I922J0D01*
G01X364351Y231287D01*
X364352D01*
G02X365023Y231063I224J-447D01*
G01X366498Y228109D01*
G01X350748D02*
X349273Y231063D01*
G03X348602Y231287I-447J-223D01*
G01X348601D01*
X347633Y230803D01*
G03X347363Y230151I652J-652D01*
G01Y224725D01*
G03X347767Y217438I65920J0D01*
G03X349229Y215107I3144J348D01*
G02X351043Y211956I-2068J-3288D01*
G01X351116Y209869D01*
X351393Y208299D01*
X353629Y205106D01*
X390038Y179612D01*
X457550Y167707D01*
X464873Y162579D01*
X470054Y155179D01*
X470277Y153885D01*
X474562Y128823D01*
X485543Y64589D01*
X485541Y64520D01*
Y64506D01*
X485532Y64204D01*
X485508Y63832D01*
X464733Y-39113D01*
X465273Y-39926D01*
X464976Y-41396D01*
X464163Y-41936D01*
X463866Y-43407D01*
X464406Y-44219D01*
X464110Y-45690D01*
X463297Y-46230D01*
X463000Y-47700D01*
X462628Y-49810D01*
Y-57639D01*
G03X463115Y-58815I1663J0D01*
G02X463602Y-59991I-1176J-1176D01*
G01Y-65809D01*
G01X362558Y235984D02*
X364038Y233031D01*
G02X363814Y232360I-448J-223D01*
G01X363812D01*
X362708Y231808D01*
G03X361913Y230150I1327J-1656D01*
G01Y224725D01*
G03X362324Y217306I67120J-3D01*
G03X364340Y214091I4337J480D01*
G02X365593Y211914I-1430J-2272D01*
G01X365669Y209743D01*
X366103Y207284D01*
X367447Y205364D01*
X399043Y183240D01*
X459128Y172647D01*
X466138Y167738D01*
X473195Y157661D01*
X473597Y155376D01*
X473598D01*
X473789Y154291D01*
X474318Y151286D01*
X474319D01*
X480897Y113973D01*
X480898D01*
X486081Y84573D01*
X489092Y67493D01*
X489521Y65068D01*
X489581Y64729D01*
X489585Y64253D01*
X470877Y-49567D01*
Y-57677D01*
G02X470876Y-57682I-1268J251D01*
G02X470491Y-58609I-1318J4D01*
G01X470389Y-58711D01*
G03X469902Y-59887I1176J-1176D01*
G01Y-65809D01*
G01X382243Y228109D02*
X380768Y231063D01*
G03X380097Y231287I-447J-223D01*
G01X380096D01*
X379128Y230803D01*
G03X378858Y230151I652J-652D01*
G01Y224725D01*
G03X379262Y217438I65920J0D01*
G03X380724Y215107I3144J348D01*
G02X382538Y211956I-2068J-3288D01*
G01X382611Y209869D01*
X382968Y207842D01*
X383435Y207175D01*
X409119Y189192D01*
X462295Y179815D01*
X469600Y174700D01*
X478541Y161930D01*
X479303Y157610D01*
X479527Y156338D01*
X495806Y64017D01*
X483111Y-37620D01*
X483710Y-38390D01*
X483524Y-39878D01*
X482754Y-40477D01*
X482568Y-41966D01*
X483167Y-42736D01*
X482981Y-44224D01*
X482211Y-44824D01*
X482005Y-46471D01*
X482000Y-46500D01*
X481525Y-49194D01*
Y-57736D01*
G03X482012Y-58912I1663J0D01*
G02X482500Y-60090I-1178J-1178D01*
G01Y-65809D01*
G01X397993Y228109D02*
X396518Y231063D01*
G03X395847Y231287I-447J-223D01*
G01X395846D01*
X394878Y230803D01*
G03X394608Y230151I652J-652D01*
G01Y224725D01*
G03X395012Y217438I65920J0D01*
G03X396474Y215107I3144J348D01*
G02X398288Y211956I-2068J-3288D01*
G01X398361Y209869D01*
X398628Y208352D01*
X399475Y207142D01*
X420871Y192159D01*
X422817Y191816D01*
X465236Y184337D01*
X475000Y177500D01*
X482444Y166866D01*
X500590Y63987D01*
X500585Y63982D01*
Y63977D01*
X500590Y62277D01*
X491715Y-40827D01*
X492343Y-41574D01*
X492214Y-43068D01*
X491468Y-43696D01*
X491339Y-45191D01*
X491967Y-45938D01*
X491839Y-47432D01*
X491092Y-48060D01*
X490761Y-51905D01*
X490974Y-57585D01*
G03X491462Y-58762I1663J0D01*
G02X491949Y-59938I-1176J-1176D01*
G01Y-65809D01*
G01X413738Y228109D02*
X412263Y231063D01*
G03X411592Y231287I-447J-223D01*
G01X411591D01*
X410623Y230803D01*
G03X410353Y230151I652J-652D01*
G01Y224725D01*
G03X410757Y217438I65920J0D01*
G03X412219Y215107I3144J348D01*
G02X414033Y211956I-2068J-3288D01*
G01X414106Y209869D01*
X414472Y207795D01*
X415071Y206940D01*
X431461Y195463D01*
X434338Y194956D01*
X467604Y189090D01*
X480300Y180200D01*
X486479Y171376D01*
X505651Y62673D01*
Y62672D01*
X505646Y62667D01*
Y62662D01*
X505650Y60962D01*
X500862Y-43155D01*
X501520Y-43876D01*
X501451Y-45374D01*
X500730Y-46032D01*
X500661Y-47530D01*
X501318Y-48251D01*
X501249Y-49749D01*
X500528Y-50407D01*
X500400Y-53200D01*
X500423Y-56334D01*
Y-57534D01*
G03X500910Y-58710I1663J0D01*
G02X501398Y-59888I-1178J-1178D01*
G01Y-65809D01*
G01X510846D02*
Y-60335D01*
G03X510359Y-59159I-1663J0D01*
G02X509872Y-57983I1176J1176D01*
G01X509778Y-55934D01*
X509747Y-55936D01*
X509346Y-53662D01*
X509905Y-52862D01*
X509645Y-51385D01*
X508845Y-50826D01*
X508585Y-49348D01*
X509145Y-48549D01*
X508884Y-47072D01*
X508085Y-46512D01*
X507824Y-45035D01*
X510800Y62200D01*
X505703Y91440D01*
X496285Y145467D01*
X491929Y170457D01*
X491440Y173259D01*
X491396Y173510D01*
X490392Y174944D01*
X490157Y175280D01*
X484400Y183500D01*
X469180Y194157D01*
X440613Y199194D01*
X432790Y204672D01*
X432378Y205089D01*
X430200Y208200D01*
X429856Y209869D01*
X429783Y211956D01*
G03X427969Y215107I-3882J-137D01*
G02X426507Y217438I1682J2679D01*
G02X426103Y224725I65516J7287D01*
G01Y230151D01*
G02X426373Y230803I922J0D01*
G01X427341Y231287D01*
X427342D01*
G02X428013Y231063I224J-447D01*
G01X429488Y228109D01*
G01X378308Y235984D02*
X379783Y233031D01*
G02X379559Y232360I-448J-223D01*
G01X379557D01*
X378453Y231808D01*
G03X377658Y230150I1327J-1656D01*
G01Y224725D01*
G03X378069Y217306I67120J-3D01*
G03X380085Y214091I4337J480D01*
G02X381338Y211914I-1430J-2272D01*
G01X381414Y209743D01*
X381832Y207372D01*
X382573Y206313D01*
X408648Y188056D01*
X461825Y178679D01*
X468738Y173838D01*
X477405Y161460D01*
X478345Y156130D01*
X494592Y63986D01*
X480818Y-46292D01*
X480325Y-49089D01*
Y-57653D01*
G02X479956Y-58544I-1260J0D01*
G01X479838Y-58663D01*
G03X479350Y-59839I1176J-1177D01*
G01Y-65809D01*
G01X394053Y235984D02*
X395533Y233031D01*
G02X395309Y232360I-448J-223D01*
G01X395307D01*
X394203Y231808D01*
G03X393408Y230150I1327J-1656D01*
G01Y224725D01*
G03X393819Y217306I67120J-3D01*
G03X395835Y214091I4337J480D01*
G02X397088Y211914I-1430J-2272D01*
G01X397164Y209743D01*
X397492Y207882D01*
X398613Y206280D01*
X420401Y191023D01*
X422950Y190574D01*
X464766Y183201D01*
X474138Y176638D01*
X481308Y166396D01*
X499371Y63987D01*
Y63986D01*
X499385Y63972D01*
Y63965D01*
X499389Y62327D01*
X489559Y-51876D01*
Y-51877D01*
X489774Y-57629D01*
Y-58043D01*
G02X489432Y-58867I-1164J0D01*
G01X489286Y-59013D01*
G03X488799Y-60190I1179J-1177D01*
G01Y-65809D01*
G01X498248D02*
Y-59841D01*
G02X498736Y-58665I1664J-1D01*
G01X498854Y-58547D01*
G03X499223Y-57654I-896J893D01*
G01X499224Y-57630D01*
X499223D01*
G02Y-57534I2864J48D01*
G01X499240Y-56535D01*
X499223Y-56342D01*
X499200Y-53208D01*
X499199Y-53177D01*
X504449Y60988D01*
X504446Y62651D01*
Y62658D01*
X504442Y62662D01*
Y62663D01*
X504432Y62673D01*
X485343Y170906D01*
X479438Y179338D01*
X467134Y187954D01*
X433868Y193820D01*
X430991Y194327D01*
X414209Y206078D01*
X413336Y207324D01*
X412909Y209743D01*
X412833Y211914D01*
G03X411580Y214091I-2683J-95D01*
G02X409564Y217306I2321J3695D01*
G02X409153Y224725I66709J7416D01*
G01Y230150D01*
G02X409948Y231808I2122J2D01*
G01X411052Y232360D01*
X411054D01*
G03X411278Y233031I-224J448D01*
G01X409803Y235984D01*
G01X507697Y-65809D02*
Y-60392D01*
G02X508184Y-59216I1663J0D01*
G03X508672Y-58038I-1178J1178D01*
G01Y-58014D01*
X508593Y-56307D01*
X508565Y-56144D01*
X506621Y-45123D01*
X509597Y62113D01*
X490259Y173040D01*
X483538Y182638D01*
X468710Y193021D01*
X440143Y198058D01*
X432013Y203751D01*
X431452Y204317D01*
X429074Y207715D01*
X428660Y209726D01*
X428583Y211914D01*
G03X427330Y214091I-2683J-95D01*
G02X425314Y217306I2321J3695D01*
G02X424903Y224725I66709J7416D01*
G01Y230150D01*
G02X425698Y231808I2122J2D01*
G01X426802Y232360D01*
X426804D01*
G03X427028Y233031I-224J448D01*
G01X425553Y235984D01*
G01X445238Y228109D02*
X443758Y231063D01*
G03X443087Y231287I-447J-223D01*
G01X443086D01*
X442118Y230803D01*
G03X441848Y230151I652J-652D01*
G01Y224725D01*
G03X442252Y217438I65920J0D01*
G03X443714Y215107I3144J348D01*
G02X445528Y211956I-2068J-3288D01*
G01X445601Y209869D01*
X446170Y206642D01*
X447393Y204895D01*
X450662Y202606D01*
X474256Y198452D01*
X488470Y188499D01*
X495255Y178808D01*
X496814Y169968D01*
X515730Y62698D01*
Y62697D01*
X515721Y62688D01*
Y60980D01*
X515400Y-31800D01*
X516989Y-42879D01*
X517637Y-46557D01*
X518437Y-47116D01*
X518697Y-48594D01*
X518137Y-49393D01*
X518398Y-50870D01*
X519197Y-51430D01*
X519458Y-52907D01*
X518898Y-53706D01*
X519321Y-56105D01*
Y-57832D01*
G03X519808Y-59008I1663J0D01*
G02X520295Y-60184I-1176J-1176D01*
G01Y-65809D01*
G01X517146D02*
Y-60143D01*
G02X517634Y-58967I1664J-1D01*
G01X517645Y-58956D01*
G03X518121Y-57805I-1152J1150D01*
G01Y-56210D01*
X515807Y-43087D01*
X515803Y-43069D01*
X514199Y-31884D01*
X514521Y60983D01*
Y62688D01*
X514511Y62698D01*
X495831Y168628D01*
Y168630D01*
X494119Y178338D01*
X487608Y187637D01*
X473786Y197316D01*
X450192Y201470D01*
X446531Y204033D01*
X445034Y206172D01*
X444404Y209743D01*
X444328Y211914D01*
G03X443075Y214091I-2683J-95D01*
G02X441059Y217306I2321J3695D01*
G02X440648Y224725I66709J7416D01*
G01Y230150D01*
G02X441443Y231808I2122J2D01*
G01X442547Y232360D01*
X442549D01*
G03X442773Y233031I-224J448D01*
G01X441298Y235984D01*
G54D27*
X36500Y74900D03*
G54D18*
X58400Y25157D03*
Y47243D03*
G54D36*
X62437Y70885D03*
G54D45*
X40794Y230682D03*
X37095Y524125D03*
X540347Y32747D03*
X572386Y532294D03*
X594107Y-26510D03*
X599868Y229462D03*
G54D55*
G01X-65001Y-234972D02*
Y-217472D01*
X-60635D01*
X-58888Y-218347D01*
X-57578Y-219514D01*
X-56486Y-221263D01*
X-55613Y-223306D01*
X-55395Y-226222D01*
X-55613Y-229139D01*
X-56486Y-231181D01*
X-57578Y-232931D01*
X-58888Y-234097D01*
X-60635Y-234972D01*
X-65001D01*
G01X-48157Y-217472D02*
X-42698Y-234972D01*
X-37239Y-217472D01*
G01X-25198D02*
Y-234972D01*
G01X-30220Y-217472D02*
X-20176D01*
G01X5435Y-234972D02*
Y-217472D01*
X10894D01*
X12640Y-218347D01*
X13732Y-219514D01*
X14169Y-221847D01*
X13732Y-224181D01*
X12422Y-225639D01*
X10894Y-226514D01*
X5435D01*
G01X10894D02*
X14169Y-234972D01*
G01X27302Y-223306D02*
Y-234972D01*
G01Y-218639D02*
X26865Y-218347D01*
Y-217764D01*
X27302Y-217472D01*
X27739Y-217764D01*
Y-218347D01*
X27302Y-218639D01*
G01X41527Y-232931D02*
X42619Y-234097D01*
X44147Y-234972D01*
X45457D01*
X46767Y-234389D01*
X47640Y-233514D01*
X48077Y-232348D01*
X47859Y-230597D01*
X46985Y-229722D01*
X43055Y-227972D01*
X42182Y-225930D01*
X42619Y-224472D01*
X43492Y-223597D01*
X44802Y-223306D01*
X46112Y-223597D01*
X47422Y-224472D01*
G01X59027Y-227097D02*
X66014D01*
X65359Y-225055D01*
X64267Y-223889D01*
X62739Y-223306D01*
X61210Y-223597D01*
X59900Y-224472D01*
X59027Y-226514D01*
X58590Y-228264D01*
Y-230014D01*
X59027Y-231764D01*
X60119Y-233514D01*
X61429Y-234680D01*
X62957Y-234972D01*
X64485Y-234389D01*
X66014Y-232639D01*
G01X76745Y-234972D02*
Y-223306D01*
G01Y-225639D02*
X77837Y-224472D01*
X78929Y-223597D01*
X80457Y-223306D01*
X81548Y-223597D01*
X82859Y-224472D01*
G01X119605Y-218931D02*
X118295Y-218055D01*
X116767Y-217472D01*
X115020D01*
X113055Y-218347D01*
X111527Y-219805D01*
X110435Y-221556D01*
X109562Y-224472D01*
X109343Y-227097D01*
X109780Y-229722D01*
X110435Y-231472D01*
X111745Y-233222D01*
X113274Y-234389D01*
X114802Y-234972D01*
X116330D01*
X117859Y-234389D01*
X119169Y-233514D01*
X120261Y-232348D01*
G01X136232Y-234972D02*
Y-223306D01*
G01Y-225347D02*
X135359Y-224181D01*
X134048Y-223597D01*
X132520Y-223306D01*
X130992Y-223889D01*
X129682Y-225055D01*
X128808Y-226805D01*
X128372Y-229139D01*
X128808Y-231472D01*
X129682Y-233222D01*
X130992Y-234389D01*
X132520Y-234972D01*
X134048Y-234680D01*
X135359Y-233806D01*
X136232Y-232639D01*
G01X146745Y-234972D02*
Y-223306D01*
G01Y-225639D02*
X147837Y-224472D01*
X148929Y-223597D01*
X150457Y-223306D01*
X151548Y-223597D01*
X152859Y-224472D01*
G01X171232Y-217472D02*
Y-234972D01*
G01Y-232348D02*
X170359Y-233806D01*
X169048Y-234680D01*
X167520Y-234972D01*
X165774Y-234389D01*
X164464Y-232931D01*
X163590Y-231181D01*
X163372Y-229139D01*
X163590Y-227097D01*
X164464Y-225347D01*
X165774Y-223889D01*
X167520Y-223306D01*
X169048Y-223597D01*
X170140Y-224181D01*
X171232Y-225347D01*
G01X178252Y-240805D02*
X191352D01*
G01X197717Y-232639D02*
X199464Y-234097D01*
X201429Y-234972D01*
X203175D01*
X204922Y-234097D01*
X206232Y-232639D01*
X206887Y-230597D01*
X206450Y-228556D01*
X205359Y-226805D01*
X203394Y-225639D01*
X200774Y-225055D01*
X199245Y-223889D01*
X198590Y-221847D01*
X199027Y-219805D01*
X200119Y-218347D01*
X201647Y-217472D01*
X203175D01*
X204704Y-218055D01*
X206014Y-219514D01*
G01X215217Y-232639D02*
X216964Y-234097D01*
X218929Y-234972D01*
X220675D01*
X222422Y-234097D01*
X223732Y-232639D01*
X224387Y-230597D01*
X223950Y-228556D01*
X222859Y-226805D01*
X220894Y-225639D01*
X218274Y-225055D01*
X216745Y-223889D01*
X216090Y-221847D01*
X216527Y-219805D01*
X217619Y-218347D01*
X219147Y-217472D01*
X220675D01*
X222204Y-218055D01*
X223514Y-219514D01*
G01X250654Y-220389D02*
X251964Y-218639D01*
X253492Y-217764D01*
X255239Y-217472D01*
X257422Y-218055D01*
X258950Y-219514D01*
X259387Y-221263D01*
X259169Y-223014D01*
X258295Y-224472D01*
X253929Y-227389D01*
X251964Y-229430D01*
X250654Y-232348D01*
X250217Y-234972D01*
X259387D01*
G01X286527Y-232931D02*
X287619Y-234097D01*
X289147Y-234972D01*
X290457D01*
X291767Y-234389D01*
X292640Y-233514D01*
X293077Y-232348D01*
X292859Y-230597D01*
X291985Y-229722D01*
X288055Y-227972D01*
X287182Y-225930D01*
X287619Y-224472D01*
X288492Y-223597D01*
X289802Y-223306D01*
X291112Y-223597D01*
X292422Y-224472D01*
G01X307302Y-234972D02*
Y-217472D01*
G01X324802Y-234972D02*
X323492Y-234680D01*
X322182Y-233514D01*
X321308Y-231472D01*
X320872Y-229139D01*
X321308Y-226805D01*
X322182Y-224764D01*
X323492Y-223597D01*
X324802Y-223306D01*
X326112Y-223597D01*
X327422Y-224764D01*
X328295Y-226805D01*
X328514Y-229139D01*
X328295Y-231472D01*
X327422Y-233514D01*
X326112Y-234680D01*
X324802Y-234972D01*
G01X342302Y-217472D02*
Y-234972D01*
G01X339245Y-223306D02*
X345359D01*
G01X356527Y-232931D02*
X357619Y-234097D01*
X359147Y-234972D01*
X360457D01*
X361767Y-234389D01*
X362640Y-233514D01*
X363077Y-232348D01*
X362859Y-230597D01*
X361985Y-229722D01*
X358055Y-227972D01*
X357182Y-225930D01*
X357619Y-224472D01*
X358492Y-223597D01*
X359802Y-223306D01*
X361112Y-223597D01*
X362422Y-224472D01*
G01X109125Y-189972D02*
Y-172472D01*
X114802Y-187055D01*
X120479Y-172472D01*
Y-189972D01*
G01X132302D02*
X130992Y-189680D01*
X129682Y-188514D01*
X128808Y-186472D01*
X128372Y-184139D01*
X128808Y-181805D01*
X129682Y-179764D01*
X130992Y-178597D01*
X132302Y-178306D01*
X133612Y-178597D01*
X134922Y-179764D01*
X135795Y-181805D01*
X136014Y-184139D01*
X135795Y-186472D01*
X134922Y-188514D01*
X133612Y-189680D01*
X132302Y-189972D01*
G01X153732Y-172472D02*
Y-189972D01*
G01Y-187348D02*
X152859Y-188806D01*
X151548Y-189680D01*
X150020Y-189972D01*
X148274Y-189389D01*
X146964Y-187931D01*
X146090Y-186181D01*
X145872Y-184139D01*
X146090Y-182097D01*
X146964Y-180347D01*
X148274Y-178889D01*
X150020Y-178306D01*
X151548Y-178597D01*
X152640Y-179181D01*
X153732Y-180347D01*
G01X164027Y-182097D02*
X171014D01*
X170359Y-180055D01*
X169267Y-178889D01*
X167739Y-178306D01*
X166210Y-178597D01*
X164900Y-179472D01*
X164027Y-181514D01*
X163590Y-183264D01*
Y-185014D01*
X164027Y-186764D01*
X165119Y-188514D01*
X166429Y-189680D01*
X167957Y-189972D01*
X169485Y-189389D01*
X171014Y-187639D01*
G01X184802Y-189972D02*
Y-172472D01*
G01X418602Y-234972D02*
Y-217472D01*
X415982Y-220972D01*
G01Y-234972D02*
X421222D01*
G01X431299Y-232348D02*
X432608Y-233806D01*
X434137Y-234680D01*
X436102Y-234972D01*
X438067Y-234389D01*
X439595Y-233222D01*
X440687Y-231181D01*
X440905Y-228847D01*
X440469Y-226514D01*
X439377Y-225055D01*
X437848Y-223889D01*
X436320Y-223597D01*
X434792Y-223889D01*
X432827Y-225055D01*
X433482Y-217472D01*
X439377D01*
G01X449890Y-232931D02*
X451419Y-234389D01*
X453165Y-234972D01*
X454912Y-234389D01*
X456440Y-232639D01*
X457532Y-230014D01*
X457969Y-227389D01*
Y-224181D01*
X457532Y-221556D01*
X456440Y-219222D01*
X455130Y-218055D01*
X453602Y-217472D01*
X451855Y-218055D01*
X450545Y-219222D01*
X449672Y-220972D01*
X449235Y-223306D01*
X449672Y-225347D01*
X450764Y-227389D01*
X452074Y-228556D01*
X453602Y-228847D01*
X455348Y-228264D01*
X456659Y-226805D01*
X457969Y-224181D01*
G01X466954Y-227681D02*
X468482Y-225639D01*
X469792Y-224472D01*
X471539Y-223889D01*
X473067Y-224472D01*
X474159Y-225639D01*
X475032Y-227389D01*
X475250Y-229430D01*
X475032Y-231181D01*
X474159Y-232931D01*
X472848Y-234389D01*
X471320Y-234972D01*
X469574Y-234389D01*
X468045Y-232639D01*
X467172Y-230014D01*
X466954Y-227097D01*
X467390Y-223306D01*
X468045Y-221263D01*
X469137Y-219222D01*
X470665Y-217764D01*
X472194Y-217472D01*
X473722Y-218055D01*
X474814Y-219514D01*
G01X488602Y-234972D02*
X490130Y-234680D01*
X491877Y-233806D01*
X492969Y-232348D01*
X493405Y-230305D01*
X492969Y-228264D01*
X491659Y-226514D01*
X489694Y-225639D01*
X487510D01*
X486200Y-225055D01*
X485108Y-223597D01*
X484672Y-221556D01*
X485327Y-219514D01*
X486855Y-218055D01*
X488602Y-217472D01*
X490348Y-218055D01*
X491877Y-219514D01*
X492532Y-221556D01*
X492095Y-223597D01*
X491004Y-225055D01*
X489694Y-225639D01*
X487510D01*
X485545Y-226514D01*
X484235Y-228264D01*
X483799Y-230305D01*
X484235Y-232348D01*
X485327Y-233806D01*
X487074Y-234680D01*
X488602Y-234972D01*
G01X405485Y-189972D02*
Y-172472D01*
X410725D01*
X412472Y-173347D01*
X413782Y-175389D01*
X414219Y-177722D01*
X413782Y-180055D01*
X412690Y-181805D01*
X410725Y-182681D01*
X405485D01*
G01X432155Y-173931D02*
X430845Y-173055D01*
X429317Y-172472D01*
X427570D01*
X425605Y-173347D01*
X424077Y-174805D01*
X422985Y-176556D01*
X422112Y-179472D01*
X421893Y-182097D01*
X422330Y-184722D01*
X422985Y-186472D01*
X424295Y-188222D01*
X425824Y-189389D01*
X427352Y-189972D01*
X428880D01*
X430409Y-189389D01*
X431719Y-188514D01*
X432811Y-187348D01*
G01X446598Y-180639D02*
X447472Y-179764D01*
X448127Y-178306D01*
X448564Y-176263D01*
X448127Y-174514D01*
X447254Y-173347D01*
X445725Y-172472D01*
X439830D01*
Y-189972D01*
X447035D01*
X448564Y-188806D01*
X449437Y-187055D01*
X449874Y-185014D01*
X449437Y-182972D01*
X448127Y-181222D01*
X446598Y-180639D01*
X439830D01*
G01X455802Y-195805D02*
X468902D01*
G01X474830Y-189972D02*
Y-172472D01*
X484874Y-189972D01*
Y-172472D01*
G01X497352Y-189972D02*
X495605Y-189680D01*
X494077Y-188514D01*
X492767Y-186764D01*
X491893Y-184722D01*
X491457Y-182389D01*
Y-180055D01*
X491893Y-177722D01*
X492767Y-175680D01*
X494077Y-173931D01*
X495605Y-172764D01*
X497352Y-172472D01*
X499098Y-172764D01*
X500627Y-173931D01*
X501937Y-175680D01*
X502811Y-177722D01*
X503247Y-180055D01*
Y-182389D01*
X502811Y-184722D01*
X501937Y-186764D01*
X500627Y-188514D01*
X499098Y-189680D01*
X497352Y-189972D01*
G01X571152Y-234972D02*
Y-217472D01*
X568532Y-220972D01*
G01Y-234972D02*
X573772D01*
G01X583193D02*
X588652Y-217472D01*
X594111Y-234972D01*
G01X592145Y-228847D02*
X585158D01*
G01X548193Y-172472D02*
X553652Y-189972D01*
X559111Y-172472D01*
G01X575519Y-189972D02*
X566785D01*
Y-172472D01*
X575519D01*
G01X572025Y-180930D02*
X566785D01*
G01X584285Y-189972D02*
Y-172472D01*
X589744D01*
X591490Y-173347D01*
X592582Y-174514D01*
X593019Y-176847D01*
X592582Y-179181D01*
X591272Y-180639D01*
X589744Y-181514D01*
X584285D01*
G01X589744D02*
X593019Y-189972D01*
G01X606152Y-190555D02*
X605715Y-190264D01*
Y-189680D01*
X606152Y-189389D01*
X606589Y-189680D01*
Y-190264D01*
X606152Y-190555D01*
G01X734219Y-217472D02*
Y-234972D01*
X725485D01*
G01X716500Y-227681D02*
X714972Y-225639D01*
X713662Y-224472D01*
X711915Y-223889D01*
X710387Y-224472D01*
X709295Y-225639D01*
X708422Y-227389D01*
X708204Y-229430D01*
X708422Y-231181D01*
X709295Y-232931D01*
X710606Y-234389D01*
X712134Y-234972D01*
X713880Y-234389D01*
X715409Y-232639D01*
X716282Y-230014D01*
X716500Y-227097D01*
X716064Y-223306D01*
X715409Y-221263D01*
X714317Y-219222D01*
X712789Y-217764D01*
X711260Y-217472D01*
X709732Y-218055D01*
X708640Y-219514D01*
G01X681735Y-172472D02*
Y-189972D01*
X690469D01*
G01X707532D02*
Y-178306D01*
G01Y-180347D02*
X706659Y-179181D01*
X705348Y-178597D01*
X703820Y-178306D01*
X702292Y-178889D01*
X700982Y-180055D01*
X700108Y-181805D01*
X699672Y-184139D01*
X700108Y-186472D01*
X700982Y-188222D01*
X702292Y-189389D01*
X703820Y-189972D01*
X705348Y-189680D01*
X706659Y-188806D01*
X707532Y-187639D01*
G01X716517Y-195222D02*
X717827Y-195805D01*
X719574Y-195222D01*
X720665Y-194056D01*
X721539Y-192597D01*
X722848Y-187931D01*
X725687Y-178306D01*
G01X718700D02*
X722848Y-187931D01*
G01X735327Y-182097D02*
X742314D01*
X741659Y-180055D01*
X740567Y-178889D01*
X739039Y-178306D01*
X737510Y-178597D01*
X736200Y-179472D01*
X735327Y-181514D01*
X734890Y-183264D01*
Y-185014D01*
X735327Y-186764D01*
X736419Y-188514D01*
X737729Y-189680D01*
X739257Y-189972D01*
X740785Y-189389D01*
X742314Y-187639D01*
G01X753045Y-189972D02*
Y-178306D01*
G01Y-180639D02*
X754137Y-179472D01*
X755229Y-178597D01*
X756757Y-178306D01*
X757848Y-178597D01*
X759159Y-179472D01*
G01X824705Y-218931D02*
X823395Y-218055D01*
X821867Y-217472D01*
X820120D01*
X818155Y-218347D01*
X816627Y-219805D01*
X815535Y-221556D01*
X814662Y-224472D01*
X814443Y-227097D01*
X814880Y-229722D01*
X815535Y-231472D01*
X816845Y-233222D01*
X818374Y-234389D01*
X819902Y-234972D01*
X821430D01*
X822959Y-234389D01*
X824269Y-233514D01*
X825361Y-232348D01*
G01X837402Y-234972D02*
X835655Y-234680D01*
X834127Y-233514D01*
X832817Y-231764D01*
X831943Y-229722D01*
X831507Y-227389D01*
Y-225055D01*
X831943Y-222722D01*
X832817Y-220680D01*
X834127Y-218931D01*
X835655Y-217764D01*
X837402Y-217472D01*
X839148Y-217764D01*
X840677Y-218931D01*
X841987Y-220680D01*
X842861Y-222722D01*
X843297Y-225055D01*
Y-227389D01*
X842861Y-229722D01*
X841987Y-231764D01*
X840677Y-233514D01*
X839148Y-234680D01*
X837402Y-234972D01*
G01X849880D02*
Y-217472D01*
X859924Y-234972D01*
Y-217472D01*
G01X867380Y-234972D02*
Y-217472D01*
X877424Y-234972D01*
Y-217472D01*
G01X887282D02*
X892522D01*
G01X889902D02*
Y-234972D01*
G01X887282D02*
X892522D01*
G01X911769D02*
X903035D01*
Y-217472D01*
X911769D01*
G01X908275Y-225930D02*
X903035D01*
G01X937817Y-234972D02*
X946987Y-217472D01*
G01X937817D02*
X946987Y-234972D01*
G01X955317D02*
Y-217472D01*
G01X964487D02*
Y-234972D01*
G01Y-226222D02*
X955317D01*
G01X823849Y-189972D02*
Y-172472D01*
X828215D01*
X829962Y-173347D01*
X831272Y-174514D01*
X832364Y-176263D01*
X833237Y-178306D01*
X833455Y-181222D01*
X833237Y-184139D01*
X832364Y-186181D01*
X831272Y-187931D01*
X829962Y-189097D01*
X828215Y-189972D01*
X823849D01*
G01X842877Y-182097D02*
X849864D01*
X849209Y-180055D01*
X848117Y-178889D01*
X846589Y-178306D01*
X845060Y-178597D01*
X843750Y-179472D01*
X842877Y-181514D01*
X842440Y-183264D01*
Y-185014D01*
X842877Y-186764D01*
X843969Y-188514D01*
X845279Y-189680D01*
X846807Y-189972D01*
X848335Y-189389D01*
X849864Y-187639D01*
G01X860377Y-187931D02*
X861469Y-189097D01*
X862997Y-189972D01*
X864307D01*
X865617Y-189389D01*
X866490Y-188514D01*
X866927Y-187348D01*
X866709Y-185597D01*
X865835Y-184722D01*
X861905Y-182972D01*
X861032Y-180930D01*
X861469Y-179472D01*
X862342Y-178597D01*
X863652Y-178306D01*
X864962Y-178597D01*
X866272Y-179472D01*
G01X881152Y-178306D02*
Y-189972D01*
G01Y-173639D02*
X880715Y-173347D01*
Y-172764D01*
X881152Y-172472D01*
X881589Y-172764D01*
Y-173347D01*
X881152Y-173639D01*
G01X895595Y-194347D02*
X897124Y-195514D01*
X898870Y-195805D01*
X900398Y-195514D01*
X901709Y-194056D01*
X902582Y-192014D01*
Y-178306D01*
G01Y-180639D02*
X901709Y-179472D01*
X900398Y-178597D01*
X898870Y-178306D01*
X897124Y-178889D01*
X896032Y-180055D01*
X895158Y-182097D01*
X894722Y-184139D01*
X894940Y-185889D01*
X895814Y-187931D01*
X897124Y-189389D01*
X898870Y-189972D01*
X900180Y-189680D01*
X901709Y-188514D01*
X902582Y-187348D01*
G01X912440Y-189972D02*
Y-178306D01*
G01Y-181222D02*
X913314Y-179764D01*
X914624Y-178597D01*
X916370Y-178306D01*
X917898Y-178597D01*
X919209Y-179764D01*
X919864Y-181805D01*
Y-189972D01*
G01X930377Y-182097D02*
X937364D01*
X936709Y-180055D01*
X935617Y-178889D01*
X934089Y-178306D01*
X932560Y-178597D01*
X931250Y-179472D01*
X930377Y-181514D01*
X929940Y-183264D01*
Y-185014D01*
X930377Y-186764D01*
X931469Y-188514D01*
X932779Y-189680D01*
X934307Y-189972D01*
X935835Y-189389D01*
X937364Y-187639D01*
G01X948095Y-189972D02*
Y-178306D01*
G01Y-180639D02*
X949187Y-179472D01*
X950279Y-178597D01*
X951807Y-178306D01*
X952898Y-178597D01*
X954209Y-179472D01*
G01X994852Y-217472D02*
X993105Y-218055D01*
X991795Y-219514D01*
X990922Y-221263D01*
X990267Y-223597D01*
X990049Y-226222D01*
X990267Y-228847D01*
X990922Y-231181D01*
X991795Y-232931D01*
X993105Y-234389D01*
X994852Y-234972D01*
X996598Y-234389D01*
X997909Y-232931D01*
X998782Y-231181D01*
X999437Y-228847D01*
X999655Y-226222D01*
X999437Y-223597D01*
X998782Y-221263D01*
X997909Y-219514D01*
X996598Y-218055D01*
X994852Y-217472D01*
G01X1012352Y-234972D02*
X1013880Y-234680D01*
X1015627Y-233806D01*
X1016719Y-232348D01*
X1017155Y-230305D01*
X1016719Y-228264D01*
X1015409Y-226514D01*
X1013444Y-225639D01*
X1011260D01*
X1009950Y-225055D01*
X1008858Y-223597D01*
X1008422Y-221556D01*
X1009077Y-219514D01*
X1010605Y-218055D01*
X1012352Y-217472D01*
X1014098Y-218055D01*
X1015627Y-219514D01*
X1016282Y-221556D01*
X1015845Y-223597D01*
X1014754Y-225055D01*
X1013444Y-225639D01*
X1011260D01*
X1009295Y-226514D01*
X1007985Y-228264D01*
X1007549Y-230305D01*
X1007985Y-232348D01*
X1009077Y-233806D01*
X1010824Y-234680D01*
X1012352Y-234972D01*
G01X1025922Y-235555D02*
X1033782Y-217472D01*
G01X1043204Y-220389D02*
X1044514Y-218639D01*
X1046042Y-217764D01*
X1047789Y-217472D01*
X1049972Y-218055D01*
X1051500Y-219514D01*
X1051937Y-221263D01*
X1051719Y-223014D01*
X1050845Y-224472D01*
X1046479Y-227389D01*
X1044514Y-229430D01*
X1043204Y-232348D01*
X1042767Y-234972D01*
X1051937D01*
G01X1060049Y-232348D02*
X1061358Y-233806D01*
X1062887Y-234680D01*
X1064852Y-234972D01*
X1066817Y-234389D01*
X1068345Y-233222D01*
X1069437Y-231181D01*
X1069655Y-228847D01*
X1069219Y-226514D01*
X1068127Y-225055D01*
X1066598Y-223889D01*
X1065070Y-223597D01*
X1063542Y-223889D01*
X1061577Y-225055D01*
X1062232Y-217472D01*
X1068127D01*
G01X1078422Y-235555D02*
X1086282Y-217472D01*
G01X1095704Y-220389D02*
X1097014Y-218639D01*
X1098542Y-217764D01*
X1100289Y-217472D01*
X1102472Y-218055D01*
X1104000Y-219514D01*
X1104437Y-221263D01*
X1104219Y-223014D01*
X1103345Y-224472D01*
X1098979Y-227389D01*
X1097014Y-229430D01*
X1095704Y-232348D01*
X1095267Y-234972D01*
X1104437D01*
G01X1117352Y-217472D02*
X1115605Y-218055D01*
X1114295Y-219514D01*
X1113422Y-221263D01*
X1112767Y-223597D01*
X1112549Y-226222D01*
X1112767Y-228847D01*
X1113422Y-231181D01*
X1114295Y-232931D01*
X1115605Y-234389D01*
X1117352Y-234972D01*
X1119098Y-234389D01*
X1120409Y-232931D01*
X1121282Y-231181D01*
X1121937Y-228847D01*
X1122155Y-226222D01*
X1121937Y-223597D01*
X1121282Y-221263D01*
X1120409Y-219514D01*
X1119098Y-218055D01*
X1117352Y-217472D01*
G01X1134852Y-234972D02*
Y-217472D01*
X1132232Y-220972D01*
G01Y-234972D02*
X1137472D01*
G01X1148204Y-227681D02*
X1149732Y-225639D01*
X1151042Y-224472D01*
X1152789Y-223889D01*
X1154317Y-224472D01*
X1155409Y-225639D01*
X1156282Y-227389D01*
X1156500Y-229430D01*
X1156282Y-231181D01*
X1155409Y-232931D01*
X1154098Y-234389D01*
X1152570Y-234972D01*
X1150824Y-234389D01*
X1149295Y-232639D01*
X1148422Y-230014D01*
X1148204Y-227097D01*
X1148640Y-223306D01*
X1149295Y-221263D01*
X1150387Y-219222D01*
X1151915Y-217764D01*
X1153444Y-217472D01*
X1154972Y-218055D01*
X1156064Y-219514D01*
G01X1042549Y-189972D02*
Y-172472D01*
X1046915D01*
X1048662Y-173347D01*
X1049972Y-174514D01*
X1051064Y-176263D01*
X1051937Y-178306D01*
X1052155Y-181222D01*
X1051937Y-184139D01*
X1051064Y-186181D01*
X1049972Y-187931D01*
X1048662Y-189097D01*
X1046915Y-189972D01*
X1042549D01*
G01X1068782D02*
Y-178306D01*
G01Y-180347D02*
X1067909Y-179181D01*
X1066598Y-178597D01*
X1065070Y-178306D01*
X1063542Y-178889D01*
X1062232Y-180055D01*
X1061358Y-181805D01*
X1060922Y-184139D01*
X1061358Y-186472D01*
X1062232Y-188222D01*
X1063542Y-189389D01*
X1065070Y-189972D01*
X1066598Y-189680D01*
X1067909Y-188806D01*
X1068782Y-187639D01*
G01X1082352Y-172472D02*
Y-189972D01*
G01X1079295Y-178306D02*
X1085409D01*
G01X1096577Y-182097D02*
X1103564D01*
X1102909Y-180055D01*
X1101817Y-178889D01*
X1100289Y-178306D01*
X1098760Y-178597D01*
X1097450Y-179472D01*
X1096577Y-181514D01*
X1096140Y-183264D01*
Y-185014D01*
X1096577Y-186764D01*
X1097669Y-188514D01*
X1098979Y-189680D01*
X1100507Y-189972D01*
X1102035Y-189389D01*
X1103564Y-187639D01*
G54D37*
X62437Y65076D03*
Y66650D03*
Y68225D03*
Y69800D03*
Y71375D03*
Y72950D03*
Y74524D03*
G54D19*
X40900Y49500D03*
G54D28*
X31200Y79000D03*
X75300Y60000D03*
X32700Y67300D03*
G54D46*
X122403Y148109D03*
X126338Y155984D03*
X130278Y148109D03*
X134213Y155984D03*
X138148Y148109D03*
X142088Y155984D03*
X146023Y148109D03*
X149963Y155984D03*
X153898Y148109D03*
X157833Y155984D03*
X161773Y148109D03*
X173583Y155984D03*
X177518Y148109D03*
X181458Y155984D03*
X185393Y148109D03*
X189333Y155984D03*
X122403Y138269D03*
X126338Y130394D03*
X130278Y138269D03*
X134213Y130394D03*
X138148Y138269D03*
X142088Y130394D03*
X146023Y138269D03*
X149963Y130394D03*
X153898Y138269D03*
X157833Y130394D03*
X161773Y138269D03*
X173583Y130394D03*
X177518Y138269D03*
X181458Y130394D03*
X185393Y138269D03*
X189333Y130394D03*
X122403Y228109D03*
X126338Y235984D03*
X130278Y228109D03*
X134213Y235984D03*
X138148Y228109D03*
X142088Y235984D03*
X146023Y228109D03*
X149963Y235984D03*
X153898Y228109D03*
X157833Y235984D03*
X161773Y228109D03*
X173583Y235984D03*
X177518Y228109D03*
X181458Y235984D03*
X185393Y228109D03*
X189333Y235984D03*
X122403Y218269D03*
X126338Y210394D03*
X130278Y218269D03*
X134213Y210394D03*
X138148Y218269D03*
X142088Y210394D03*
X146023Y218269D03*
X149963Y210394D03*
X153898Y218269D03*
X157833Y210394D03*
X161773Y218269D03*
X173583Y210394D03*
X177518Y218269D03*
X181458Y210394D03*
X185393Y218269D03*
X189333Y210394D03*
X193268Y148109D03*
X197203Y155984D03*
X201143Y148109D03*
X205078Y155984D03*
X209018Y148109D03*
X212953Y155984D03*
X216888Y148109D03*
X220828Y155984D03*
X224763Y148109D03*
X228703Y155984D03*
X232638Y148109D03*
X236573Y155984D03*
X240513Y148109D03*
X244448Y155984D03*
X248388Y148109D03*
X252323Y155984D03*
X256258Y148109D03*
X260198Y155984D03*
X264133Y148109D03*
X268073Y155984D03*
X193268Y138269D03*
X197203Y130394D03*
X201143Y138269D03*
X205078Y130394D03*
X209018Y138269D03*
X212953Y130394D03*
X216888Y138269D03*
X220828Y130394D03*
X224763Y138269D03*
X228703Y130394D03*
X232638Y138269D03*
X236573Y130394D03*
X240513Y138269D03*
X244448Y130394D03*
X248388Y138269D03*
X252323Y130394D03*
X256258Y138269D03*
X260198Y130394D03*
X264133Y138269D03*
X268073Y130394D03*
X193268Y228109D03*
X197203Y235984D03*
X201143Y228109D03*
X205078Y235984D03*
X209018Y228109D03*
X212953Y235984D03*
X216888Y228109D03*
X220828Y235984D03*
X224763Y228109D03*
X228703Y235984D03*
X232638Y228109D03*
X236573Y235984D03*
X240513Y228109D03*
X244448Y235984D03*
X248388Y228109D03*
X252323Y235984D03*
X256258Y228109D03*
X260198Y235984D03*
X264133Y228109D03*
X268073Y235984D03*
X193268Y218269D03*
X197203Y210394D03*
X201143Y218269D03*
X205078Y210394D03*
X209018Y218269D03*
X212953Y210394D03*
X216888Y218269D03*
X220828Y210394D03*
X224763Y218269D03*
X228703Y210394D03*
X232638Y218269D03*
X236573Y210394D03*
X240513Y218269D03*
X244448Y210394D03*
X248388Y218269D03*
X252323Y210394D03*
X256258Y218269D03*
X260198Y210394D03*
X264133Y218269D03*
X268073Y210394D03*
X272008Y148109D03*
X275943Y155984D03*
X279883Y148109D03*
X283818Y155984D03*
X287758Y148109D03*
X291693Y155984D03*
X295628Y148109D03*
X299568Y155984D03*
X303503Y148109D03*
X307443Y155984D03*
X311378Y148109D03*
X315313Y155984D03*
X319253Y148109D03*
X323188Y155984D03*
X327128Y148109D03*
X331063Y155984D03*
X334998Y148109D03*
X338938Y155984D03*
X342873Y148109D03*
X346813Y155984D03*
X272008Y138269D03*
X275943Y130394D03*
X279883Y138269D03*
X283818Y130394D03*
X287758Y138269D03*
X291693Y130394D03*
X295628Y138269D03*
X299568Y130394D03*
X303503Y138269D03*
X307443Y130394D03*
X311378Y138269D03*
X315313Y130394D03*
X319253Y138269D03*
X323188Y130394D03*
X327128Y138269D03*
X331063Y130394D03*
X334998Y138269D03*
X338938Y130394D03*
X342873Y138269D03*
X346813Y130394D03*
X272008Y228109D03*
X275943Y235984D03*
X279883Y228109D03*
X283818Y235984D03*
X287758Y228109D03*
X291693Y235984D03*
X295628Y228109D03*
X299568Y235984D03*
X303503Y228109D03*
X307443Y235984D03*
X311378Y228109D03*
X315313Y235984D03*
X319253Y228109D03*
X323188Y235984D03*
X327128Y228109D03*
X331063Y235984D03*
X334998Y228109D03*
X338938Y235984D03*
X342873Y228109D03*
X346813Y235984D03*
X272008Y218269D03*
X275943Y210394D03*
X279883Y218269D03*
X283818Y210394D03*
X287758Y218269D03*
X291693Y210394D03*
X295628Y218269D03*
X299568Y210394D03*
X303503Y218269D03*
X307443Y210394D03*
X311378Y218269D03*
X315313Y210394D03*
X319253Y218269D03*
X323188Y210394D03*
X327128Y218269D03*
X331063Y210394D03*
X334998Y218269D03*
X338938Y210394D03*
X342873Y218269D03*
X346813Y210394D03*
X350748Y148109D03*
X354683Y155984D03*
X358623Y148109D03*
X362558Y155984D03*
X366498Y148109D03*
X370433Y155984D03*
X374368Y148109D03*
X378308Y155984D03*
X382243Y148109D03*
X386183Y155984D03*
X390118Y148109D03*
X394053Y155984D03*
X397993Y148109D03*
X401928Y155984D03*
X405868Y148109D03*
X409803Y155984D03*
X413738Y148109D03*
X417678Y155984D03*
X421613Y148109D03*
X425553Y155984D03*
X429488Y148109D03*
X350748Y138269D03*
X354683Y130394D03*
X358623Y138269D03*
X362558Y130394D03*
X366498Y138269D03*
X370433Y130394D03*
X374368Y138269D03*
X378308Y130394D03*
X382243Y138269D03*
X386183Y130394D03*
X390118Y138269D03*
X394053Y130394D03*
X397993Y138269D03*
X401928Y130394D03*
X405868Y138269D03*
X409803Y130394D03*
X413738Y138269D03*
X417678Y130394D03*
X421613Y138269D03*
X425553Y130394D03*
X429488Y138269D03*
X350748Y228109D03*
X354683Y235984D03*
X358623Y228109D03*
X362558Y235984D03*
X366498Y228109D03*
X370433Y235984D03*
X374368Y228109D03*
X378308Y235984D03*
X382243Y228109D03*
X386183Y235984D03*
X390118Y228109D03*
X394053Y235984D03*
X397993Y228109D03*
X401928Y235984D03*
X405868Y228109D03*
X409803Y235984D03*
X413738Y228109D03*
X417678Y235984D03*
X421613Y228109D03*
X425553Y235984D03*
X429488Y228109D03*
X350748Y218269D03*
X354683Y210394D03*
X358623Y218269D03*
X362558Y210394D03*
X366498Y218269D03*
X370433Y210394D03*
X374368Y218269D03*
X378308Y210394D03*
X382243Y218269D03*
X386183Y210394D03*
X390118Y218269D03*
X394053Y210394D03*
X397993Y218269D03*
X401928Y210394D03*
X405868Y218269D03*
X409803Y210394D03*
X413738Y218269D03*
X417678Y210394D03*
X421613Y218269D03*
X425553Y210394D03*
X429488Y218269D03*
X433423Y155984D03*
X437363Y148109D03*
X441298Y155984D03*
X445238Y148109D03*
X449173Y155984D03*
X433423Y130394D03*
X437363Y138269D03*
X441298Y130394D03*
X445238Y138269D03*
X449173Y130394D03*
X433423Y235984D03*
X437363Y228109D03*
X441298Y235984D03*
X445238Y228109D03*
X449173Y235984D03*
X433423Y210394D03*
X437363Y218269D03*
X441298Y210394D03*
X445238Y218269D03*
X449173Y210394D03*
G54D56*
G01X51563Y71375D02*
X45125D01*
X44500Y70750D01*
G01X36800Y59750D02*
X38750Y61700D01*
X45100D01*
X48476Y65076D01*
X51563D01*
G01X48326Y74524D02*
X51563D01*
G01Y68225D02*
X47325D01*
X46300Y67200D01*
G01X44500Y64500D02*
X45450Y65450D01*
X46650D01*
X47850Y66650D01*
X51563D01*
G01Y72950D02*
X47150D01*
X45850Y74250D01*
X44500D01*
G01X44800Y68700D02*
X45800D01*
X46900Y69800D01*
X51563D01*
G54D38*
X55819Y75234D03*
Y64366D03*
X58181D03*
G54D29*
X34600Y79000D03*
X78700Y60000D03*
X36100Y67300D03*
G54D47*
X444705Y-64309D03*
X447854D03*
X451004D03*
X454154D03*
X457303D03*
X460453D03*
X463602D03*
X466752D03*
X469902D03*
X473051D03*
X476201D03*
X479350D03*
X482500D03*
X485650D03*
X488799D03*
X491949D03*
X495098D03*
X498248D03*
X501398D03*
X504547D03*
X507697D03*
X510846D03*
X513996D03*
X517146D03*
X520295D03*
X523445D03*
X526594D03*
X529744D03*
X532894D03*
X536043D03*
G54D48*
X539370Y190256D03*
Y206792D03*
X561024Y190256D03*
Y206792D03*
G54D39*
X51663Y63107D03*
G54D49*
G01X26400Y42900D02*
X24400Y44900D01*
Y59600D01*
G01X87300Y28500D02*
X93100D01*
X94400Y27200D01*
Y20300D01*
X91400Y17300D01*
X37100D01*
X26400Y28000D01*
Y42900D01*
G01X85100Y30700D02*
X87300Y28500D01*
G01X45046Y59300D02*
X48853Y63107D01*
X51563D01*
G01X79600Y63900D02*
X78400D01*
X75250Y60750D01*
Y60000D01*
G01X66975Y61575D02*
X65443Y63107D01*
X62437D01*
G01X55500Y168400D02*
Y165150D01*
X56400Y164250D01*
G01X188900Y173300D02*
X191400Y170800D01*
X222400D01*
X225100Y168100D01*
G01X517900Y157400D02*
Y157100D01*
X520500Y154500D01*
M02*
